(kicad_sch
	(version 20250114)
	(generator "eeschema")
	(generator_version "9.0")
	(paper "A3")
	(title_block
		(title "PolarFire SoM")
		(date "2025-07-22")
		(rev "1.1.4")
		(company "Antmicro Ltd")
		(comment 1 "www.antmicro.com")
	)
	(text "PolarFire Bank 1\nGPIO"
		(exclude_from_sim no)
		(at 13.335 26.035 0)
		(effects
			(font
				(size 4 4)
				(thickness 0.8)
				(bold yes)
			)
			(justify left bottom)
		)
	)
	(text "2-lane CSI works only when VDDI = 1V8"
		(exclude_from_sim no)
		(at 31.75 41.91 0)
		(effects
			(font
				(size 1.27 1.27)
			)
			(justify left bottom)
		)
	)
	(text "USER LED"
		(exclude_from_sim no)
		(at 22.86 189.23 0)
		(effects
			(font
				(size 4 4)
				(thickness 0.8)
				(bold yes)
			)
			(justify left bottom)
		)
	)
	(text "Logic shifters"
		(exclude_from_sim no)
		(at 266.065 30.48 0)
		(effects
			(font
				(size 4 4)
				(thickness 0.8)
				(bold yes)
			)
			(justify left bottom)
		)
	)
	(junction
		(at 332.74 102.87)
		(diameter 0)
		(color 0 0 0 0)
	)
	(junction
		(at 36.83 254)
		(diameter 0)
		(color 0 0 0 0)
	)
	(junction
		(at 66.04 254)
		(diameter 0)
		(color 0 0 0 0)
	)
	(junction
		(at 307.34 102.87)
		(diameter 0)
		(color 0 0 0 0)
	)
	(junction
		(at 308.61 78.74)
		(diameter 0)
		(color 0 0 0 0)
	)
	(junction
		(at 29.21 246.38)
		(diameter 0)
		(color 0 0 0 0)
	)
	(junction
		(at 307.34 40.64)
		(diameter 0)
		(color 0 0 0 0)
	)
	(junction
		(at 86.36 246.38)
		(diameter 0)
		(color 0 0 0 0)
	)
	(junction
		(at 133.35 259.08)
		(diameter 0)
		(color 0 0 0 0)
	)
	(junction
		(at 133.35 204.47)
		(diameter 0)
		(color 0 0 0 0)
	)
	(junction
		(at 308.61 222.25)
		(diameter 0)
		(color 0 0 0 0)
	)
	(junction
		(at 58.42 246.38)
		(diameter 0)
		(color 0 0 0 0)
	)
	(junction
		(at 133.35 231.14)
		(diameter 0)
		(color 0 0 0 0)
	)
	(junction
		(at 93.98 255.27)
		(diameter 0)
		(color 0 0 0 0)
	)
	(junction
		(at 309.88 148.59)
		(diameter 0)
		(color 0 0 0 0)
	)
	(junction
		(at 332.74 40.64)
		(diameter 0)
		(color 0 0 0 0)
	)
	(no_connect
		(at 167.64 63.5)
	)
	(no_connect
		(at 76.2 71.12)
	)
	(no_connect
		(at 167.64 114.3)
	)
	(no_connect
		(at 167.64 147.32)
	)
	(no_connect
		(at 76.2 104.14)
	)
	(no_connect
		(at 167.64 58.42)
	)
	(no_connect
		(at 167.64 81.28)
	)
	(no_connect
		(at 167.64 109.22)
	)
	(no_connect
		(at 76.2 88.9)
	)
	(no_connect
		(at 76.2 101.6)
	)
	(no_connect
		(at 167.64 149.86)
	)
	(no_connect
		(at 76.2 93.98)
	)
	(no_connect
		(at 76.2 68.58)
	)
	(no_connect
		(at 167.64 111.76)
	)
	(no_connect
		(at 167.64 91.44)
	)
	(bus_entry
		(at 226.06 71.12)
		(size 2.54 -2.54)
		(stroke
			(width 0)
			(type default)
		)
	)
	(bus_entry
		(at 172.72 233.68)
		(size 2.54 -2.54)
		(stroke
			(width 0)
			(type default)
		)
	)
	(bus_entry
		(at 172.72 261.62)
		(size 2.54 -2.54)
		(stroke
			(width 0)
			(type default)
		)
	)
	(bus_entry
		(at 212.09 119.38)
		(size 2.54 -2.54)
		(stroke
			(width 0)
			(type default)
		)
	)
	(bus_entry
		(at 226.06 68.58)
		(size 2.54 -2.54)
		(stroke
			(width 0)
			(type default)
		)
	)
	(bus_entry
		(at 353.06 54.61)
		(size -2.54 2.54)
		(stroke
			(width 0)
			(type default)
		)
	)
	(bus_entry
		(at 43.18 59.69)
		(size 1.27 1.27)
		(stroke
			(width 0)
			(type default)
		)
	)
	(bus_entry
		(at 353.06 52.07)
		(size -2.54 2.54)
		(stroke
			(width 0)
			(type default)
		)
	)
	(bus_entry
		(at 212.09 127)
		(size 2.54 -2.54)
		(stroke
			(width 0)
			(type default)
		)
	)
	(bus_entry
		(at 187.96 60.96)
		(size 2.54 -2.54)
		(stroke
			(width 0)
			(type default)
		)
	)
	(bus_entry
		(at 350.52 153.67)
		(size 2.54 -2.54)
		(stroke
			(width 0)
			(type default)
		)
	)
	(bus_entry
		(at 189.23 116.84)
		(size 1.27 -1.27)
		(stroke
			(width 0)
			(type default)
		)
	)
	(bus_entry
		(at 226.06 76.2)
		(size 2.54 -2.54)
		(stroke
			(width 0)
			(type default)
		)
	)
	(bus_entry
		(at 212.09 121.92)
		(size 2.54 -2.54)
		(stroke
			(width 0)
			(type default)
		)
	)
	(bus_entry
		(at 353.06 81.28)
		(size -2.54 2.54)
		(stroke
			(width 0)
			(type default)
		)
	)
	(bus_entry
		(at 62.23 49.53)
		(size 1.27 1.27)
		(stroke
			(width 0)
			(type default)
		)
	)
	(bus_entry
		(at 62.23 52.07)
		(size 1.27 1.27)
		(stroke
			(width 0)
			(type default)
		)
	)
	(bus_entry
		(at 189.23 129.54)
		(size 1.27 -1.27)
		(stroke
			(width 0)
			(type default)
		)
	)
	(bus_entry
		(at 43.18 57.15)
		(size 1.27 1.27)
		(stroke
			(width 0)
			(type default)
		)
	)
	(bus_entry
		(at 212.09 124.46)
		(size 2.54 -2.54)
		(stroke
			(width 0)
			(type default)
		)
	)
	(bus_entry
		(at 226.06 73.66)
		(size 2.54 -2.54)
		(stroke
			(width 0)
			(type default)
		)
	)
	(bus_entry
		(at 353.06 78.74)
		(size -2.54 2.54)
		(stroke
			(width 0)
			(type default)
		)
	)
	(bus_entry
		(at 172.72 236.22)
		(size 2.54 -2.54)
		(stroke
			(width 0)
			(type default)
		)
	)
	(bus_entry
		(at 172.72 264.16)
		(size 2.54 -2.54)
		(stroke
			(width 0)
			(type default)
		)
	)
	(bus_entry
		(at 172.72 209.55)
		(size 2.54 -2.54)
		(stroke
			(width 0)
			(type default)
		)
	)
	(bus_entry
		(at 62.23 62.23)
		(size 1.27 1.27)
		(stroke
			(width 0)
			(type default)
		)
	)
	(bus_entry
		(at 62.23 46.99)
		(size 1.27 1.27)
		(stroke
			(width 0)
			(type default)
		)
	)
	(bus_entry
		(at 226.06 96.52)
		(size 2.54 -2.54)
		(stroke
			(width 0)
			(type default)
		)
	)
	(bus_entry
		(at 226.06 93.98)
		(size 2.54 -2.54)
		(stroke
			(width 0)
			(type default)
		)
	)
	(bus_entry
		(at 350.52 151.13)
		(size 2.54 -2.54)
		(stroke
			(width 0)
			(type default)
		)
	)
	(bus_entry
		(at 172.72 207.01)
		(size 2.54 -2.54)
		(stroke
			(width 0)
			(type default)
		)
	)
	(bus_entry
		(at 62.23 54.61)
		(size 1.27 1.27)
		(stroke
			(width 0)
			(type default)
		)
	)
	(bus_entry
		(at 62.23 64.77)
		(size 1.27 1.27)
		(stroke
			(width 0)
			(type default)
		)
	)
	(wire
		(pts
			(xy 378.46 228.6) (xy 378.46 229.87)
		)
		(stroke
			(width 0)
			(type default)
		)
	)
	(wire
		(pts
			(xy 309.88 52.07) (xy 311.15 52.07)
		)
		(stroke
			(width 0)
			(type default)
		)
	)
	(wire
		(pts
			(xy 93.98 255.27) (xy 93.98 256.54)
		)
		(stroke
			(width 0)
			(type default)
		)
	)
	(wire
		(pts
			(xy 172.72 207.01) (xy 154.94 207.01)
		)
		(stroke
			(width 0)
			(type default)
		)
	)
	(wire
		(pts
			(xy 71.12 137.16) (xy 76.2 137.16)
		)
		(stroke
			(width 0)
			(type default)
		)
	)
	(wire
		(pts
			(xy 156.21 203.2) (xy 156.21 204.47)
		)
		(stroke
			(width 0)
			(type default)
		)
	)
	(wire
		(pts
			(xy 63.5 66.04) (xy 76.2 66.04)
		)
		(stroke
			(width 0)
			(type default)
		)
	)
	(wire
		(pts
			(xy 63.5 50.8) (xy 76.2 50.8)
		)
		(stroke
			(width 0)
			(type default)
		)
	)
	(wire
		(pts
			(xy 332.74 156.21) (xy 331.47 156.21)
		)
		(stroke
			(width 0)
			(type default)
		)
	)
	(wire
		(pts
			(xy 36.83 248.92) (xy 36.83 254)
		)
		(stroke
			(width 0)
			(type default)
		)
	)
	(wire
		(pts
			(xy 309.88 144.78) (xy 309.88 148.59)
		)
		(stroke
			(width 0)
			(type default)
		)
	)
	(wire
		(pts
			(xy 119.38 233.68) (xy 134.62 233.68)
		)
		(stroke
			(width 0)
			(type default)
		)
	)
	(wire
		(pts
			(xy 133.35 231.14) (xy 133.35 238.76)
		)
		(stroke
			(width 0)
			(type default)
		)
	)
	(wire
		(pts
			(xy 63.5 53.34) (xy 76.2 53.34)
		)
		(stroke
			(width 0)
			(type default)
		)
	)
	(wire
		(pts
			(xy 185.42 223.52) (xy 185.42 226.06)
		)
		(stroke
			(width 0)
			(type default)
		)
	)
	(wire
		(pts
			(xy 86.36 246.38) (xy 86.36 248.92)
		)
		(stroke
			(width 0)
			(type default)
		)
	)
	(wire
		(pts
			(xy 332.74 121.92) (xy 332.74 125.73)
		)
		(stroke
			(width 0)
			(type default)
		)
	)
	(wire
		(pts
			(xy 93.98 232.41) (xy 93.98 238.76)
		)
		(stroke
			(width 0)
			(type default)
		)
	)
	(wire
		(pts
			(xy 309.88 40.64) (xy 307.34 40.64)
		)
		(stroke
			(width 0)
			(type default)
		)
	)
	(wire
		(pts
			(xy 71.12 134.62) (xy 76.2 134.62)
		)
		(stroke
			(width 0)
			(type default)
		)
	)
	(bus
		(pts
			(xy 193.04 55.88) (xy 191.77 55.88)
		)
		(stroke
			(width 0)
			(type default)
		)
	)
	(wire
		(pts
			(xy 167.64 142.24) (xy 218.44 142.24)
		)
		(stroke
			(width 0)
			(type default)
		)
	)
	(wire
		(pts
			(xy 156.21 259.08) (xy 154.94 259.08)
		)
		(stroke
			(width 0)
			(type default)
		)
	)
	(wire
		(pts
			(xy 69.85 224.79) (xy 93.98 224.79)
		)
		(stroke
			(width 0)
			(type default)
		)
	)
	(wire
		(pts
			(xy 36.83 224.79) (xy 62.23 224.79)
		)
		(stroke
			(width 0)
			(type default)
		)
	)
	(wire
		(pts
			(xy 167.64 53.34) (xy 187.96 53.34)
		)
		(stroke
			(width 0)
			(type default)
		)
	)
	(wire
		(pts
			(xy 193.04 223.52) (xy 193.04 226.06)
		)
		(stroke
			(width 0)
			(type default)
		)
	)
	(wire
		(pts
			(xy 167.64 129.54) (xy 189.23 129.54)
		)
		(stroke
			(width 0)
			(type default)
		)
	)
	(wire
		(pts
			(xy 167.64 104.14) (xy 187.96 104.14)
		)
		(stroke
			(width 0)
			(type default)
		)
	)
	(wire
		(pts
			(xy 36.83 254) (xy 36.83 255.27)
		)
		(stroke
			(width 0)
			(type default)
		)
	)
	(bus
		(pts
			(xy 228.6 73.66) (xy 228.6 91.44)
		)
		(stroke
			(width 0)
			(type default)
		)
	)
	(wire
		(pts
			(xy 167.64 76.2) (xy 226.06 76.2)
		)
		(stroke
			(width 0)
			(type default)
		)
	)
	(wire
		(pts
			(xy 335.28 224.79) (xy 331.47 224.79)
		)
		(stroke
			(width 0)
			(type default)
		)
	)
	(wire
		(pts
			(xy 167.64 99.06) (xy 185.42 99.06)
		)
		(stroke
			(width 0)
			(type default)
		)
	)
	(wire
		(pts
			(xy 332.74 148.59) (xy 331.47 148.59)
		)
		(stroke
			(width 0)
			(type default)
		)
	)
	(wire
		(pts
			(xy 332.74 101.6) (xy 332.74 102.87)
		)
		(stroke
			(width 0)
			(type default)
		)
	)
	(wire
		(pts
			(xy 378.46 222.25) (xy 378.46 223.52)
		)
		(stroke
			(width 0)
			(type default)
		)
	)
	(wire
		(pts
			(xy 167.64 134.62) (xy 172.72 134.62)
		)
		(stroke
			(width 0)
			(type default)
		)
	)
	(wire
		(pts
			(xy 193.04 231.14) (xy 193.04 233.68)
		)
		(stroke
			(width 0)
			(type default)
		)
	)
	(wire
		(pts
			(xy 156.21 229.87) (xy 156.21 231.14)
		)
		(stroke
			(width 0)
			(type default)
		)
	)
	(wire
		(pts
			(xy 309.88 102.87) (xy 309.88 114.3)
		)
		(stroke
			(width 0)
			(type default)
		)
	)
	(wire
		(pts
			(xy 307.34 102.87) (xy 304.8 102.87)
		)
		(stroke
			(width 0)
			(type default)
		)
	)
	(wire
		(pts
			(xy 332.74 59.69) (xy 332.74 63.5)
		)
		(stroke
			(width 0)
			(type default)
		)
	)
	(wire
		(pts
			(xy 335.28 227.33) (xy 331.47 227.33)
		)
		(stroke
			(width 0)
			(type default)
		)
	)
	(bus
		(pts
			(xy 190.5 114.3) (xy 190.5 115.57)
		)
		(stroke
			(width 0)
			(type default)
		)
	)
	(wire
		(pts
			(xy 290.83 227.33) (xy 311.15 227.33)
		)
		(stroke
			(width 0)
			(type default)
		)
	)
	(wire
		(pts
			(xy 307.34 101.6) (xy 307.34 102.87)
		)
		(stroke
			(width 0)
			(type default)
		)
	)
	(wire
		(pts
			(xy 156.21 257.81) (xy 156.21 259.08)
		)
		(stroke
			(width 0)
			(type default)
		)
	)
	(wire
		(pts
			(xy 308.61 78.74) (xy 311.15 78.74)
		)
		(stroke
			(width 0)
			(type default)
		)
	)
	(wire
		(pts
			(xy 154.94 236.22) (xy 172.72 236.22)
		)
		(stroke
			(width 0)
			(type default)
		)
	)
	(bus
		(pts
			(xy 43.18 57.15) (xy 43.18 59.69)
		)
		(stroke
			(width 0)
			(type default)
		)
	)
	(bus
		(pts
			(xy 175.26 233.68) (xy 175.26 259.08)
		)
		(stroke
			(width 0)
			(type default)
		)
	)
	(bus
		(pts
			(xy 228.6 68.58) (xy 228.6 71.12)
		)
		(stroke
			(width 0)
			(type default)
		)
	)
	(wire
		(pts
			(xy 311.15 229.87) (xy 308.61 229.87)
		)
		(stroke
			(width 0)
			(type default)
		)
	)
	(wire
		(pts
			(xy 29.21 246.38) (xy 29.21 247.65)
		)
		(stroke
			(width 0)
			(type default)
		)
	)
	(wire
		(pts
			(xy 40.64 147.32) (xy 76.2 147.32)
		)
		(stroke
			(width 0)
			(type default)
		)
	)
	(bus
		(pts
			(xy 62.23 49.53) (xy 62.23 52.07)
		)
		(stroke
			(width 0)
			(type default)
		)
	)
	(wire
		(pts
			(xy 167.64 121.92) (xy 212.09 121.92)
		)
		(stroke
			(width 0)
			(type default)
		)
	)
	(wire
		(pts
			(xy 308.61 229.87) (xy 308.61 222.25)
		)
		(stroke
			(width 0)
			(type default)
		)
	)
	(wire
		(pts
			(xy 308.61 219.71) (xy 308.61 222.25)
		)
		(stroke
			(width 0)
			(type default)
		)
	)
	(wire
		(pts
			(xy 44.45 58.42) (xy 76.2 58.42)
		)
		(stroke
			(width 0)
			(type default)
		)
	)
	(wire
		(pts
			(xy 167.64 78.74) (xy 172.72 78.74)
		)
		(stroke
			(width 0)
			(type default)
		)
	)
	(wire
		(pts
			(xy 156.21 266.7) (xy 154.94 266.7)
		)
		(stroke
			(width 0)
			(type default)
		)
	)
	(wire
		(pts
			(xy 332.74 40.64) (xy 335.28 40.64)
		)
		(stroke
			(width 0)
			(type default)
		)
	)
	(wire
		(pts
			(xy 311.15 194.31) (xy 312.42 194.31)
		)
		(stroke
			(width 0)
			(type default)
		)
	)
	(bus
		(pts
			(xy 353.06 148.59) (xy 353.06 151.13)
		)
		(stroke
			(width 0)
			(type default)
		)
	)
	(wire
		(pts
			(xy 334.01 86.36) (xy 331.47 86.36)
		)
		(stroke
			(width 0)
			(type default)
		)
	)
	(wire
		(pts
			(xy 332.74 102.87) (xy 331.47 102.87)
		)
		(stroke
			(width 0)
			(type default)
		)
	)
	(wire
		(pts
			(xy 167.64 88.9) (xy 172.72 88.9)
		)
		(stroke
			(width 0)
			(type default)
		)
	)
	(wire
		(pts
			(xy 71.12 129.54) (xy 76.2 129.54)
		)
		(stroke
			(width 0)
			(type default)
		)
	)
	(wire
		(pts
			(xy 311.15 148.59) (xy 309.88 148.59)
		)
		(stroke
			(width 0)
			(type default)
		)
	)
	(wire
		(pts
			(xy 71.12 91.44) (xy 76.2 91.44)
		)
		(stroke
			(width 0)
			(type default)
		)
	)
	(bus
		(pts
			(xy 41.91 54.61) (xy 43.18 55.88)
		)
		(stroke
			(width 0)
			(type default)
		)
	)
	(wire
		(pts
			(xy 44.45 246.38) (xy 58.42 246.38)
		)
		(stroke
			(width 0)
			(type default)
		)
	)
	(wire
		(pts
			(xy 73.66 246.38) (xy 86.36 246.38)
		)
		(stroke
			(width 0)
			(type default)
		)
	)
	(wire
		(pts
			(xy 294.64 191.77) (xy 312.42 191.77)
		)
		(stroke
			(width 0)
			(type default)
		)
	)
	(wire
		(pts
			(xy 383.54 78.74) (xy 383.54 80.01)
		)
		(stroke
			(width 0)
			(type default)
		)
	)
	(wire
		(pts
			(xy 71.12 114.3) (xy 76.2 114.3)
		)
		(stroke
			(width 0)
			(type default)
		)
	)
	(wire
		(pts
			(xy 330.2 194.31) (xy 330.2 195.58)
		)
		(stroke
			(width 0)
			(type default)
		)
	)
	(wire
		(pts
			(xy 167.64 73.66) (xy 226.06 73.66)
		)
		(stroke
			(width 0)
			(type default)
		)
	)
	(wire
		(pts
			(xy 86.36 246.38) (xy 87.63 246.38)
		)
		(stroke
			(width 0)
			(type default)
		)
	)
	(wire
		(pts
			(xy 311.15 86.36) (xy 308.61 86.36)
		)
		(stroke
			(width 0)
			(type default)
		)
	)
	(wire
		(pts
			(xy 71.12 111.76) (xy 76.2 111.76)
		)
		(stroke
			(width 0)
			(type default)
		)
	)
	(wire
		(pts
			(xy 134.62 259.08) (xy 133.35 259.08)
		)
		(stroke
			(width 0)
			(type default)
		)
	)
	(wire
		(pts
			(xy 167.64 93.98) (xy 226.06 93.98)
		)
		(stroke
			(width 0)
			(type default)
		)
	)
	(wire
		(pts
			(xy 331.47 57.15) (xy 350.52 57.15)
		)
		(stroke
			(width 0)
			(type default)
		)
	)
	(bus
		(pts
			(xy 190.5 57.15) (xy 190.5 58.42)
		)
		(stroke
			(width 0)
			(type default)
		)
	)
	(wire
		(pts
			(xy 367.03 222.25) (xy 367.03 223.52)
		)
		(stroke
			(width 0)
			(type default)
		)
	)
	(bus
		(pts
			(xy 228.6 66.04) (xy 228.6 68.58)
		)
		(stroke
			(width 0)
			(type default)
		)
	)
	(wire
		(pts
			(xy 307.34 40.64) (xy 307.34 59.69)
		)
		(stroke
			(width 0)
			(type default)
		)
	)
	(bus
		(pts
			(xy 354.33 49.53) (xy 353.06 50.8)
		)
		(stroke
			(width 0)
			(type default)
		)
	)
	(wire
		(pts
			(xy 29.21 254) (xy 36.83 254)
		)
		(stroke
			(width 0)
			(type default)
		)
	)
	(wire
		(pts
			(xy 331.47 54.61) (xy 350.52 54.61)
		)
		(stroke
			(width 0)
			(type default)
		)
	)
	(polyline
		(pts
			(xy 308.61 177.8) (xy 309.88 179.07)
		)
		(stroke
			(width 0)
			(type default)
		)
	)
	(wire
		(pts
			(xy 58.42 254) (xy 66.04 254)
		)
		(stroke
			(width 0)
			(type default)
		)
	)
	(wire
		(pts
			(xy 373.38 85.09) (xy 373.38 86.36)
		)
		(stroke
			(width 0)
			(type default)
		)
	)
	(wire
		(pts
			(xy 309.88 102.87) (xy 307.34 102.87)
		)
		(stroke
			(width 0)
			(type default)
		)
	)
	(wire
		(pts
			(xy 308.61 76.2) (xy 308.61 78.74)
		)
		(stroke
			(width 0)
			(type default)
		)
	)
	(polyline
		(pts
			(xy 309.88 134.62) (xy 311.15 135.89)
		)
		(stroke
			(width 0)
			(type default)
		)
	)
	(bus
		(pts
			(xy 353.06 147.32) (xy 354.33 146.05)
		)
		(stroke
			(width 0)
			(type default)
		)
	)
	(wire
		(pts
			(xy 328.93 191.77) (xy 331.47 191.77)
		)
		(stroke
			(width 0)
			(type default)
		)
	)
	(wire
		(pts
			(xy 307.34 39.37) (xy 307.34 40.64)
		)
		(stroke
			(width 0)
			(type default)
		)
	)
	(wire
		(pts
			(xy 185.42 231.14) (xy 185.42 233.68)
		)
		(stroke
			(width 0)
			(type default)
		)
	)
	(wire
		(pts
			(xy 332.74 102.87) (xy 335.28 102.87)
		)
		(stroke
			(width 0)
			(type default)
		)
	)
	(bus
		(pts
			(xy 228.6 71.12) (xy 228.6 73.66)
		)
		(stroke
			(width 0)
			(type default)
		)
	)
	(wire
		(pts
			(xy 133.35 229.87) (xy 133.35 231.14)
		)
		(stroke
			(width 0)
			(type default)
		)
	)
	(bus
		(pts
			(xy 175.26 204.47) (xy 175.26 207.01)
		)
		(stroke
			(width 0)
			(type default)
		)
	)
	(wire
		(pts
			(xy 71.12 116.84) (xy 76.2 116.84)
		)
		(stroke
			(width 0)
			(type default)
		)
	)
	(wire
		(pts
			(xy 16.51 246.38) (xy 29.21 246.38)
		)
		(stroke
			(width 0)
			(type default)
		)
	)
	(bus
		(pts
			(xy 355.6 49.53) (xy 354.33 49.53)
		)
		(stroke
			(width 0)
			(type default)
		)
	)
	(wire
		(pts
			(xy 311.15 189.23) (xy 312.42 189.23)
		)
		(stroke
			(width 0)
			(type default)
		)
	)
	(wire
		(pts
			(xy 311.15 187.96) (xy 311.15 189.23)
		)
		(stroke
			(width 0)
			(type default)
		)
	)
	(wire
		(pts
			(xy 373.38 78.74) (xy 373.38 80.01)
		)
		(stroke
			(width 0)
			(type default)
		)
	)
	(wire
		(pts
			(xy 154.94 261.62) (xy 172.72 261.62)
		)
		(stroke
			(width 0)
			(type default)
		)
	)
	(bus
		(pts
			(xy 214.63 115.57) (xy 214.63 116.84)
		)
		(stroke
			(width 0)
			(type default)
		)
	)
	(wire
		(pts
			(xy 71.12 127) (xy 76.2 127)
		)
		(stroke
			(width 0)
			(type default)
		)
	)
	(wire
		(pts
			(xy 334.01 229.87) (xy 331.47 229.87)
		)
		(stroke
			(width 0)
			(type default)
		)
	)
	(wire
		(pts
			(xy 167.64 106.68) (xy 185.42 106.68)
		)
		(stroke
			(width 0)
			(type default)
		)
	)
	(wire
		(pts
			(xy 167.64 96.52) (xy 226.06 96.52)
		)
		(stroke
			(width 0)
			(type default)
		)
	)
	(wire
		(pts
			(xy 365.76 171.45) (xy 365.76 172.72)
		)
		(stroke
			(width 0)
			(type default)
		)
	)
	(bus
		(pts
			(xy 175.26 259.08) (xy 175.26 261.62)
		)
		(stroke
			(width 0)
			(type default)
		)
	)
	(wire
		(pts
			(xy 36.83 232.41) (xy 36.83 238.76)
		)
		(stroke
			(width 0)
			(type default)
		)
	)
	(bus
		(pts
			(xy 176.53 201.93) (xy 177.8 201.93)
		)
		(stroke
			(width 0)
			(type default)
		)
	)
	(wire
		(pts
			(xy 134.62 204.47) (xy 133.35 204.47)
		)
		(stroke
			(width 0)
			(type default)
		)
	)
	(wire
		(pts
			(xy 311.15 54.61) (xy 297.18 54.61)
		)
		(stroke
			(width 0)
			(type default)
		)
	)
	(wire
		(pts
			(xy 332.74 39.37) (xy 332.74 40.64)
		)
		(stroke
			(width 0)
			(type default)
		)
	)
	(wire
		(pts
			(xy 334.01 88.9) (xy 334.01 86.36)
		)
		(stroke
			(width 0)
			(type default)
		)
	)
	(wire
		(pts
			(xy 71.12 124.46) (xy 76.2 124.46)
		)
		(stroke
			(width 0)
			(type default)
		)
	)
	(bus
		(pts
			(xy 353.06 50.8) (xy 353.06 52.07)
		)
		(stroke
			(width 0)
			(type default)
		)
	)
	(wire
		(pts
			(xy 66.04 203.2) (xy 66.04 204.47)
		)
		(stroke
			(width 0)
			(type default)
		)
	)
	(wire
		(pts
			(xy 40.64 139.7) (xy 76.2 139.7)
		)
		(stroke
			(width 0)
			(type default)
		)
	)
	(wire
		(pts
			(xy 119.38 209.55) (xy 134.62 209.55)
		)
		(stroke
			(width 0)
			(type default)
		)
	)
	(wire
		(pts
			(xy 156.21 238.76) (xy 156.21 240.03)
		)
		(stroke
			(width 0)
			(type default)
		)
	)
	(wire
		(pts
			(xy 334.01 219.71) (xy 334.01 222.25)
		)
		(stroke
			(width 0)
			(type default)
		)
	)
	(wire
		(pts
			(xy 311.15 57.15) (xy 297.18 57.15)
		)
		(stroke
			(width 0)
			(type default)
		)
	)
	(wire
		(pts
			(xy 167.64 68.58) (xy 226.06 68.58)
		)
		(stroke
			(width 0)
			(type default)
		)
	)
	(wire
		(pts
			(xy 71.12 106.68) (xy 76.2 106.68)
		)
		(stroke
			(width 0)
			(type default)
		)
	)
	(polyline
		(pts
			(xy 334.01 134.62) (xy 332.74 135.89)
		)
		(stroke
			(width 0)
			(type default)
		)
	)
	(wire
		(pts
			(xy 330.2 187.96) (xy 330.2 189.23)
		)
		(stroke
			(width 0)
			(type default)
		)
	)
	(wire
		(pts
			(xy 40.64 152.4) (xy 76.2 152.4)
		)
		(stroke
			(width 0)
			(type default)
		)
	)
	(bus
		(pts
			(xy 40.64 54.61) (xy 41.91 54.61)
		)
		(stroke
			(width 0)
			(type default)
		)
	)
	(wire
		(pts
			(xy 134.62 266.7) (xy 133.35 266.7)
		)
		(stroke
			(width 0)
			(type default)
		)
	)
	(wire
		(pts
			(xy 156.21 212.09) (xy 156.21 213.36)
		)
		(stroke
			(width 0)
			(type default)
		)
	)
	(bus
		(pts
			(xy 217.17 114.3) (xy 215.9 114.3)
		)
		(stroke
			(width 0)
			(type default)
		)
	)
	(polyline
		(pts
			(xy 334.01 134.62) (xy 309.88 134.62)
		)
		(stroke
			(width 0)
			(type default)
		)
	)
	(bus
		(pts
			(xy 175.26 207.01) (xy 175.26 231.14)
		)
		(stroke
			(width 0)
			(type default)
		)
	)
	(wire
		(pts
			(xy 167.64 101.6) (xy 185.42 101.6)
		)
		(stroke
			(width 0)
			(type default)
		)
	)
	(wire
		(pts
			(xy 134.62 238.76) (xy 133.35 238.76)
		)
		(stroke
			(width 0)
			(type default)
		)
	)
	(wire
		(pts
			(xy 86.36 255.27) (xy 86.36 254)
		)
		(stroke
			(width 0)
			(type default)
		)
	)
	(wire
		(pts
			(xy 365.76 165.1) (xy 365.76 166.37)
		)
		(stroke
			(width 0)
			(type default)
		)
	)
	(wire
		(pts
			(xy 288.29 116.84) (xy 311.15 116.84)
		)
		(stroke
			(width 0)
			(type default)
		)
	)
	(polyline
		(pts
			(xy 309.88 134.62) (xy 311.15 133.35)
		)
		(stroke
			(width 0)
			(type default)
		)
	)
	(wire
		(pts
			(xy 335.28 45.72) (xy 335.28 48.26)
		)
		(stroke
			(width 0)
			(type default)
		)
	)
	(wire
		(pts
			(xy 133.35 203.2) (xy 133.35 204.47)
		)
		(stroke
			(width 0)
			(type default)
		)
	)
	(wire
		(pts
			(xy 167.64 152.4) (xy 172.72 152.4)
		)
		(stroke
			(width 0)
			(type default)
		)
	)
	(wire
		(pts
			(xy 167.64 66.04) (xy 172.72 66.04)
		)
		(stroke
			(width 0)
			(type default)
		)
	)
	(bus
		(pts
			(xy 191.77 113.03) (xy 193.04 113.03)
		)
		(stroke
			(width 0)
			(type default)
		)
	)
	(wire
		(pts
			(xy 331.47 222.25) (xy 334.01 222.25)
		)
		(stroke
			(width 0)
			(type default)
		)
	)
	(bus
		(pts
			(xy 231.14 63.5) (xy 229.87 63.5)
		)
		(stroke
			(width 0)
			(type default)
		)
	)
	(bus
		(pts
			(xy 214.63 116.84) (xy 214.63 119.38)
		)
		(stroke
			(width 0)
			(type default)
		)
	)
	(wire
		(pts
			(xy 156.21 231.14) (xy 154.94 231.14)
		)
		(stroke
			(width 0)
			(type default)
		)
	)
	(wire
		(pts
			(xy 350.52 83.82) (xy 331.47 83.82)
		)
		(stroke
			(width 0)
			(type default)
		)
	)
	(wire
		(pts
			(xy 59.69 73.66) (xy 76.2 73.66)
		)
		(stroke
			(width 0)
			(type default)
		)
	)
	(wire
		(pts
			(xy 71.12 121.92) (xy 76.2 121.92)
		)
		(stroke
			(width 0)
			(type default)
		)
	)
	(bus
		(pts
			(xy 60.96 44.45) (xy 62.23 45.72)
		)
		(stroke
			(width 0)
			(type default)
		)
	)
	(wire
		(pts
			(xy 71.12 109.22) (xy 76.2 109.22)
		)
		(stroke
			(width 0)
			(type default)
		)
	)
	(wire
		(pts
			(xy 167.64 55.88) (xy 187.96 55.88)
		)
		(stroke
			(width 0)
			(type default)
		)
	)
	(wire
		(pts
			(xy 332.74 114.3) (xy 331.47 114.3)
		)
		(stroke
			(width 0)
			(type default)
		)
	)
	(wire
		(pts
			(xy 309.88 40.64) (xy 309.88 52.07)
		)
		(stroke
			(width 0)
			(type default)
		)
	)
	(wire
		(pts
			(xy 309.88 148.59) (xy 309.88 156.21)
		)
		(stroke
			(width 0)
			(type default)
		)
	)
	(wire
		(pts
			(xy 332.74 147.32) (xy 332.74 148.59)
		)
		(stroke
			(width 0)
			(type default)
		)
	)
	(wire
		(pts
			(xy 309.88 114.3) (xy 311.15 114.3)
		)
		(stroke
			(width 0)
			(type default)
		)
	)
	(wire
		(pts
			(xy 331.47 151.13) (xy 350.52 151.13)
		)
		(stroke
			(width 0)
			(type default)
		)
	)
	(wire
		(pts
			(xy 134.62 231.14) (xy 133.35 231.14)
		)
		(stroke
			(width 0)
			(type default)
		)
	)
	(wire
		(pts
			(xy 167.64 116.84) (xy 189.23 116.84)
		)
		(stroke
			(width 0)
			(type default)
		)
	)
	(bus
		(pts
			(xy 176.53 201.93) (xy 175.26 203.2)
		)
		(stroke
			(width 0)
			(type default)
		)
	)
	(wire
		(pts
			(xy 58.42 254) (xy 58.42 252.73)
		)
		(stroke
			(width 0)
			(type default)
		)
	)
	(wire
		(pts
			(xy 167.64 144.78) (xy 218.44 144.78)
		)
		(stroke
			(width 0)
			(type default)
		)
	)
	(wire
		(pts
			(xy 69.85 223.52) (xy 69.85 224.79)
		)
		(stroke
			(width 0)
			(type default)
		)
	)
	(wire
		(pts
			(xy 308.61 222.25) (xy 311.15 222.25)
		)
		(stroke
			(width 0)
			(type default)
		)
	)
	(wire
		(pts
			(xy 62.23 224.79) (xy 62.23 223.52)
		)
		(stroke
			(width 0)
			(type default)
		)
	)
	(wire
		(pts
			(xy 167.64 124.46) (xy 212.09 124.46)
		)
		(stroke
			(width 0)
			(type default)
		)
	)
	(bus
		(pts
			(xy 354.33 76.2) (xy 353.06 77.47)
		)
		(stroke
			(width 0)
			(type default)
		)
	)
	(wire
		(pts
			(xy 156.21 238.76) (xy 154.94 238.76)
		)
		(stroke
			(width 0)
			(type default)
		)
	)
	(wire
		(pts
			(xy 167.64 83.82) (xy 172.72 83.82)
		)
		(stroke
			(width 0)
			(type default)
		)
	)
	(wire
		(pts
			(xy 154.94 233.68) (xy 172.72 233.68)
		)
		(stroke
			(width 0)
			(type default)
		)
	)
	(wire
		(pts
			(xy 134.62 212.09) (xy 133.35 212.09)
		)
		(stroke
			(width 0)
			(type default)
		)
	)
	(wire
		(pts
			(xy 293.37 83.82) (xy 311.15 83.82)
		)
		(stroke
			(width 0)
			(type default)
		)
	)
	(wire
		(pts
			(xy 334.01 76.2) (xy 334.01 78.74)
		)
		(stroke
			(width 0)
			(type default)
		)
	)
	(bus
		(pts
			(xy 228.6 91.44) (xy 228.6 93.98)
		)
		(stroke
			(width 0)
			(type default)
		)
	)
	(wire
		(pts
			(xy 71.12 99.06) (xy 76.2 99.06)
		)
		(stroke
			(width 0)
			(type default)
		)
	)
	(wire
		(pts
			(xy 167.64 60.96) (xy 187.96 60.96)
		)
		(stroke
			(width 0)
			(type default)
		)
	)
	(wire
		(pts
			(xy 167.64 119.38) (xy 212.09 119.38)
		)
		(stroke
			(width 0)
			(type default)
		)
	)
	(wire
		(pts
			(xy 156.21 212.09) (xy 154.94 212.09)
		)
		(stroke
			(width 0)
			(type default)
		)
	)
	(wire
		(pts
			(xy 334.01 232.41) (xy 334.01 229.87)
		)
		(stroke
			(width 0)
			(type default)
		)
	)
	(wire
		(pts
			(xy 36.83 227.33) (xy 36.83 224.79)
		)
		(stroke
			(width 0)
			(type default)
		)
	)
	(wire
		(pts
			(xy 167.64 132.08) (xy 172.72 132.08)
		)
		(stroke
			(width 0)
			(type default)
		)
	)
	(bus
		(pts
			(xy 62.23 54.61) (xy 62.23 62.23)
		)
		(stroke
			(width 0)
			(type default)
		)
	)
	(wire
		(pts
			(xy 349.25 119.38) (xy 331.47 119.38)
		)
		(stroke
			(width 0)
			(type default)
		)
	)
	(wire
		(pts
			(xy 330.2 194.31) (xy 328.93 194.31)
		)
		(stroke
			(width 0)
			(type default)
		)
	)
	(wire
		(pts
			(xy 133.35 257.81) (xy 133.35 259.08)
		)
		(stroke
			(width 0)
			(type default)
		)
	)
	(bus
		(pts
			(xy 62.23 62.23) (xy 62.23 64.77)
		)
		(stroke
			(width 0)
			(type default)
		)
	)
	(wire
		(pts
			(xy 154.94 264.16) (xy 172.72 264.16)
		)
		(stroke
			(width 0)
			(type default)
		)
	)
	(wire
		(pts
			(xy 44.45 60.96) (xy 76.2 60.96)
		)
		(stroke
			(width 0)
			(type default)
		)
	)
	(wire
		(pts
			(xy 40.64 144.78) (xy 76.2 144.78)
		)
		(stroke
			(width 0)
			(type default)
		)
	)
	(wire
		(pts
			(xy 290.83 224.79) (xy 311.15 224.79)
		)
		(stroke
			(width 0)
			(type default)
		)
	)
	(wire
		(pts
			(xy 66.04 232.41) (xy 66.04 238.76)
		)
		(stroke
			(width 0)
			(type default)
		)
	)
	(wire
		(pts
			(xy 332.74 156.21) (xy 332.74 157.48)
		)
		(stroke
			(width 0)
			(type default)
		)
	)
	(bus
		(pts
			(xy 214.63 121.92) (xy 214.63 124.46)
		)
		(stroke
			(width 0)
			(type default)
		)
	)
	(bus
		(pts
			(xy 353.06 78.74) (xy 353.06 81.28)
		)
		(stroke
			(width 0)
			(type default)
		)
	)
	(bus
		(pts
			(xy 214.63 115.57) (xy 215.9 114.3)
		)
		(stroke
			(width 0)
			(type default)
		)
	)
	(bus
		(pts
			(xy 190.5 114.3) (xy 191.77 113.03)
		)
		(stroke
			(width 0)
			(type default)
		)
	)
	(wire
		(pts
			(xy 93.98 224.79) (xy 93.98 227.33)
		)
		(stroke
			(width 0)
			(type default)
		)
	)
	(wire
		(pts
			(xy 59.69 76.2) (xy 76.2 76.2)
		)
		(stroke
			(width 0)
			(type default)
		)
	)
	(bus
		(pts
			(xy 354.33 76.2) (xy 355.6 76.2)
		)
		(stroke
			(width 0)
			(type default)
		)
	)
	(wire
		(pts
			(xy 63.5 55.88) (xy 76.2 55.88)
		)
		(stroke
			(width 0)
			(type default)
		)
	)
	(wire
		(pts
			(xy 119.38 207.01) (xy 134.62 207.01)
		)
		(stroke
			(width 0)
			(type default)
		)
	)
	(wire
		(pts
			(xy 311.15 59.69) (xy 307.34 59.69)
		)
		(stroke
			(width 0)
			(type default)
		)
	)
	(wire
		(pts
			(xy 330.2 189.23) (xy 328.93 189.23)
		)
		(stroke
			(width 0)
			(type default)
		)
	)
	(wire
		(pts
			(xy 331.47 153.67) (xy 350.52 153.67)
		)
		(stroke
			(width 0)
			(type default)
		)
	)
	(bus
		(pts
			(xy 175.26 203.2) (xy 175.26 204.47)
		)
		(stroke
			(width 0)
			(type default)
		)
	)
	(polyline
		(pts
			(xy 334.01 134.62) (xy 332.74 133.35)
		)
		(stroke
			(width 0)
			(type default)
		)
	)
	(bus
		(pts
			(xy 190.5 115.57) (xy 190.5 128.27)
		)
		(stroke
			(width 0)
			(type default)
		)
	)
	(wire
		(pts
			(xy 86.36 255.27) (xy 93.98 255.27)
		)
		(stroke
			(width 0)
			(type default)
		)
	)
	(wire
		(pts
			(xy 332.74 40.64) (xy 332.74 52.07)
		)
		(stroke
			(width 0)
			(type default)
		)
	)
	(wire
		(pts
			(xy 59.69 78.74) (xy 76.2 78.74)
		)
		(stroke
			(width 0)
			(type default)
		)
	)
	(wire
		(pts
			(xy 332.74 121.92) (xy 331.47 121.92)
		)
		(stroke
			(width 0)
			(type default)
		)
	)
	(bus
		(pts
			(xy 354.33 146.05) (xy 355.6 146.05)
		)
		(stroke
			(width 0)
			(type default)
		)
	)
	(wire
		(pts
			(xy 335.28 107.95) (xy 335.28 110.49)
		)
		(stroke
			(width 0)
			(type default)
		)
	)
	(bus
		(pts
			(xy 62.23 52.07) (xy 62.23 54.61)
		)
		(stroke
			(width 0)
			(type default)
		)
	)
	(wire
		(pts
			(xy 133.35 259.08) (xy 133.35 266.7)
		)
		(stroke
			(width 0)
			(type default)
		)
	)
	(wire
		(pts
			(xy 350.52 81.28) (xy 331.47 81.28)
		)
		(stroke
			(width 0)
			(type default)
		)
	)
	(wire
		(pts
			(xy 309.88 156.21) (xy 311.15 156.21)
		)
		(stroke
			(width 0)
			(type default)
		)
	)
	(wire
		(pts
			(xy 93.98 248.92) (xy 93.98 255.27)
		)
		(stroke
			(width 0)
			(type default)
		)
	)
	(wire
		(pts
			(xy 29.21 246.38) (xy 30.48 246.38)
		)
		(stroke
			(width 0)
			(type default)
		)
	)
	(wire
		(pts
			(xy 71.12 96.52) (xy 76.2 96.52)
		)
		(stroke
			(width 0)
			(type default)
		)
	)
	(wire
		(pts
			(xy 40.64 149.86) (xy 76.2 149.86)
		)
		(stroke
			(width 0)
			(type default)
		)
	)
	(wire
		(pts
			(xy 71.12 132.08) (xy 76.2 132.08)
		)
		(stroke
			(width 0)
			(type default)
		)
	)
	(wire
		(pts
			(xy 119.38 264.16) (xy 134.62 264.16)
		)
		(stroke
			(width 0)
			(type default)
		)
	)
	(bus
		(pts
			(xy 214.63 119.38) (xy 214.63 121.92)
		)
		(stroke
			(width 0)
			(type default)
		)
	)
	(wire
		(pts
			(xy 156.21 204.47) (xy 154.94 204.47)
		)
		(stroke
			(width 0)
			(type default)
		)
	)
	(wire
		(pts
			(xy 304.8 107.95) (xy 304.8 110.49)
		)
		(stroke
			(width 0)
			(type default)
		)
	)
	(wire
		(pts
			(xy 167.64 50.8) (xy 187.96 50.8)
		)
		(stroke
			(width 0)
			(type default)
		)
	)
	(wire
		(pts
			(xy 332.74 102.87) (xy 332.74 114.3)
		)
		(stroke
			(width 0)
			(type default)
		)
	)
	(wire
		(pts
			(xy 332.74 52.07) (xy 331.47 52.07)
		)
		(stroke
			(width 0)
			(type default)
		)
	)
	(bus
		(pts
			(xy 228.6 64.77) (xy 228.6 66.04)
		)
		(stroke
			(width 0)
			(type default)
		)
	)
	(wire
		(pts
			(xy 58.42 246.38) (xy 59.69 246.38)
		)
		(stroke
			(width 0)
			(type default)
		)
	)
	(bus
		(pts
			(xy 62.23 45.72) (xy 62.23 46.99)
		)
		(stroke
			(width 0)
			(type default)
		)
	)
	(bus
		(pts
			(xy 59.69 44.45) (xy 60.96 44.45)
		)
		(stroke
			(width 0)
			(type default)
		)
	)
	(wire
		(pts
			(xy 59.69 81.28) (xy 76.2 81.28)
		)
		(stroke
			(width 0)
			(type default)
		)
	)
	(wire
		(pts
			(xy 63.5 48.26) (xy 76.2 48.26)
		)
		(stroke
			(width 0)
			(type default)
		)
	)
	(wire
		(pts
			(xy 119.38 261.62) (xy 134.62 261.62)
		)
		(stroke
			(width 0)
			(type default)
		)
	)
	(bus
		(pts
			(xy 353.06 52.07) (xy 353.06 54.61)
		)
		(stroke
			(width 0)
			(type default)
		)
	)
	(wire
		(pts
			(xy 133.35 204.47) (xy 133.35 212.09)
		)
		(stroke
			(width 0)
			(type default)
		)
	)
	(bus
		(pts
			(xy 228.6 64.77) (xy 229.87 63.5)
		)
		(stroke
			(width 0)
			(type default)
		)
	)
	(polyline
		(pts
			(xy 308.61 177.8) (xy 309.88 176.53)
		)
		(stroke
			(width 0)
			(type default)
		)
	)
	(wire
		(pts
			(xy 292.1 151.13) (xy 311.15 151.13)
		)
		(stroke
			(width 0)
			(type default)
		)
	)
	(wire
		(pts
			(xy 383.54 85.09) (xy 383.54 86.36)
		)
		(stroke
			(width 0)
			(type default)
		)
	)
	(wire
		(pts
			(xy 154.94 209.55) (xy 172.72 209.55)
		)
		(stroke
			(width 0)
			(type default)
		)
	)
	(bus
		(pts
			(xy 62.23 46.99) (xy 62.23 49.53)
		)
		(stroke
			(width 0)
			(type default)
		)
	)
	(wire
		(pts
			(xy 304.8 45.72) (xy 304.8 48.26)
		)
		(stroke
			(width 0)
			(type default)
		)
	)
	(wire
		(pts
			(xy 359.41 165.1) (xy 359.41 166.37)
		)
		(stroke
			(width 0)
			(type default)
		)
	)
	(wire
		(pts
			(xy 359.41 171.45) (xy 359.41 172.72)
		)
		(stroke
			(width 0)
			(type default)
		)
	)
	(wire
		(pts
			(xy 307.34 102.87) (xy 307.34 121.92)
		)
		(stroke
			(width 0)
			(type default)
		)
	)
	(wire
		(pts
			(xy 63.5 63.5) (xy 76.2 63.5)
		)
		(stroke
			(width 0)
			(type default)
		)
	)
	(wire
		(pts
			(xy 66.04 254) (xy 66.04 255.27)
		)
		(stroke
			(width 0)
			(type default)
		)
	)
	(bus
		(pts
			(xy 191.77 55.88) (xy 190.5 57.15)
		)
		(stroke
			(width 0)
			(type default)
		)
	)
	(bus
		(pts
			(xy 353.06 77.47) (xy 353.06 78.74)
		)
		(stroke
			(width 0)
			(type default)
		)
	)
	(wire
		(pts
			(xy 367.03 228.6) (xy 367.03 229.87)
		)
		(stroke
			(width 0)
			(type default)
		)
	)
	(wire
		(pts
			(xy 167.64 137.16) (xy 172.72 137.16)
		)
		(stroke
			(width 0)
			(type default)
		)
	)
	(wire
		(pts
			(xy 331.47 78.74) (xy 334.01 78.74)
		)
		(stroke
			(width 0)
			(type default)
		)
	)
	(bus
		(pts
			(xy 175.26 231.14) (xy 175.26 233.68)
		)
		(stroke
			(width 0)
			(type default)
		)
	)
	(wire
		(pts
			(xy 119.38 236.22) (xy 134.62 236.22)
		)
		(stroke
			(width 0)
			(type default)
		)
	)
	(wire
		(pts
			(xy 293.37 81.28) (xy 311.15 81.28)
		)
		(stroke
			(width 0)
			(type default)
		)
	)
	(wire
		(pts
			(xy 71.12 119.38) (xy 76.2 119.38)
		)
		(stroke
			(width 0)
			(type default)
		)
	)
	(wire
		(pts
			(xy 29.21 254) (xy 29.21 252.73)
		)
		(stroke
			(width 0)
			(type default)
		)
	)
	(wire
		(pts
			(xy 167.64 139.7) (xy 218.44 139.7)
		)
		(stroke
			(width 0)
			(type default)
		)
	)
	(wire
		(pts
			(xy 311.15 194.31) (xy 311.15 195.58)
		)
		(stroke
			(width 0)
			(type default)
		)
	)
	(wire
		(pts
			(xy 167.64 127) (xy 212.09 127)
		)
		(stroke
			(width 0)
			(type default)
		)
	)
	(wire
		(pts
			(xy 292.1 153.67) (xy 311.15 153.67)
		)
		(stroke
			(width 0)
			(type default)
		)
	)
	(wire
		(pts
			(xy 167.64 86.36) (xy 172.72 86.36)
		)
		(stroke
			(width 0)
			(type default)
		)
	)
	(polyline
		(pts
			(xy 308.61 177.8) (xy 331.47 177.8)
		)
		(stroke
			(width 0)
			(type default)
		)
	)
	(wire
		(pts
			(xy 71.12 86.36) (xy 76.2 86.36)
		)
		(stroke
			(width 0)
			(type default)
		)
	)
	(wire
		(pts
			(xy 308.61 86.36) (xy 308.61 78.74)
		)
		(stroke
			(width 0)
			(type default)
		)
	)
	(bus
		(pts
			(xy 353.06 147.32) (xy 353.06 148.59)
		)
		(stroke
			(width 0)
			(type default)
		)
	)
	(wire
		(pts
			(xy 58.42 246.38) (xy 58.42 247.65)
		)
		(stroke
			(width 0)
			(type default)
		)
	)
	(wire
		(pts
			(xy 66.04 248.92) (xy 66.04 254)
		)
		(stroke
			(width 0)
			(type default)
		)
	)
	(wire
		(pts
			(xy 307.34 121.92) (xy 311.15 121.92)
		)
		(stroke
			(width 0)
			(type default)
		)
	)
	(wire
		(pts
			(xy 307.34 40.64) (xy 304.8 40.64)
		)
		(stroke
			(width 0)
			(type default)
		)
	)
	(bus
		(pts
			(xy 43.18 55.88) (xy 43.18 57.15)
		)
		(stroke
			(width 0)
			(type default)
		)
	)
	(wire
		(pts
			(xy 167.64 48.26) (xy 187.96 48.26)
		)
		(stroke
			(width 0)
			(type default)
		)
	)
	(wire
		(pts
			(xy 167.64 71.12) (xy 226.06 71.12)
		)
		(stroke
			(width 0)
			(type default)
		)
	)
	(wire
		(pts
			(xy 71.12 83.82) (xy 76.2 83.82)
		)
		(stroke
			(width 0)
			(type default)
		)
	)
	(wire
		(pts
			(xy 332.74 59.69) (xy 331.47 59.69)
		)
		(stroke
			(width 0)
			(type default)
		)
	)
	(wire
		(pts
			(xy 40.64 142.24) (xy 76.2 142.24)
		)
		(stroke
			(width 0)
			(type default)
		)
	)
	(wire
		(pts
			(xy 349.25 116.84) (xy 331.47 116.84)
		)
		(stroke
			(width 0)
			(type default)
		)
	)
	(wire
		(pts
			(xy 66.04 223.52) (xy 66.04 227.33)
		)
		(stroke
			(width 0)
			(type default)
		)
	)
	(wire
		(pts
			(xy 156.21 266.7) (xy 156.21 267.97)
		)
		(stroke
			(width 0)
			(type default)
		)
	)
	(wire
		(pts
			(xy 288.29 119.38) (xy 311.15 119.38)
		)
		(stroke
			(width 0)
			(type default)
		)
	)
	(label "WiFi_CMD"
		(at 40.64 139.7 0)
		(effects
			(font
				(size 1.27 1.27)
			)
			(justify left bottom)
		)
	)
	(label "WiFi_DATA_3"
		(at 119.38 236.22 0)
		(effects
			(font
				(size 1.27 1.27)
			)
			(justify left bottom)
		)
	)
	(label "PCIe_CLK_nREQ_PF"
		(at 187.96 48.26 180)
		(effects
			(font
				(size 1.27 1.27)
			)
			(justify right bottom)
		)
	)
	(label "Crosslink.CS"
		(at 211.455 121.92 180)
		(effects
			(font
				(size 1.27 1.27)
			)
			(justify right bottom)
		)
	)
	(label "CAM0.D1_P"
		(at 64.77 53.34 0)
		(effects
			(font
				(size 1.27 1.27)
			)
			(justify left bottom)
		)
	)
	(label "WiFi_DATA_1"
		(at 119.38 209.55 0)
		(effects
			(font
				(size 1.27 1.27)
			)
			(justify left bottom)
		)
	)
	(label "WiFi.CLK"
		(at 172.085 264.16 180)
		(effects
			(font
				(size 1.27 1.27)
			)
			(justify right bottom)
		)
	)
	(label "WiFi.DAT0"
		(at 171.45 233.68 180)
		(effects
			(font
				(size 1.27 1.27)
			)
			(justify right bottom)
		)
	)
	(label "HDMI0_HPD_SRC"
		(at 185.42 106.68 180)
		(effects
			(font
				(size 1.27 1.27)
			)
			(justify right bottom)
		)
	)
	(label "PF_ETH_MDIO"
		(at 59.69 76.2 0)
		(effects
			(font
				(size 1.27 1.27)
			)
			(justify left bottom)
		)
	)
	(label "USER_LED_G"
		(at 44.45 246.38 0)
		(effects
			(font
				(size 1.27 1.27)
			)
			(justify left bottom)
		)
	)
	(label "PCIe_nRST_PF"
		(at 187.96 50.8 180)
		(effects
			(font
				(size 1.27 1.27)
			)
			(justify right bottom)
		)
	)
	(label "HDMI0_SCL_SRC"
		(at 185.42 101.6 180)
		(effects
			(font
				(size 1.27 1.27)
			)
			(justify right bottom)
		)
	)
	(label "CAM0.D0_P"
		(at 64.77 48.26 0)
		(effects
			(font
				(size 1.27 1.27)
			)
			(justify left bottom)
		)
	)
	(label "ETH.MDIO"
		(at 335.28 83.82 0)
		(effects
			(font
				(size 1.27 1.27)
			)
			(justify left bottom)
		)
	)
	(label "SDA0_PF"
		(at 297.18 57.15 0)
		(effects
			(font
				(size 1.27 1.27)
			)
			(justify left bottom)
		)
	)
	(label "HDMI_FPGA.TX2_N"
		(at 221.615 96.52 180)
		(effects
			(font
				(size 1.27 1.27)
			)
			(justify right bottom)
		)
	)
	(label "WiFi_DATA_0"
		(at 119.38 233.68 0)
		(effects
			(font
				(size 1.27 1.27)
			)
			(justify left bottom)
		)
	)
	(label "ULPI.RESET"
		(at 170.815 60.96 0)
		(effects
			(font
				(size 1.27 1.27)
			)
			(justify left bottom)
		)
	)
	(label "PF_ETH_RESET_n"
		(at 290.83 227.33 0)
		(effects
			(font
				(size 1.27 1.27)
			)
			(justify left bottom)
		)
	)
	(label "Crosslink.SCL"
		(at 189.23 129.54 180)
		(effects
			(font
				(size 1.27 1.27)
			)
			(justify right bottom)
		)
	)
	(label "HDMI_FPGA.CLK_N"
		(at 44.45 60.96 0)
		(effects
			(font
				(size 1.27 1.27)
			)
			(justify left bottom)
		)
	)
	(label "HDMI_FPGA.TX1_P"
		(at 221.615 73.66 180)
		(effects
			(font
				(size 1.27 1.27)
			)
			(justify right bottom)
		)
	)
	(label "I^{2}C0.SDA"
		(at 349.885 57.15 180)
		(effects
			(font
				(size 1.27 1.27)
			)
			(justify right bottom)
		)
	)
	(label "CAM0.D0_N"
		(at 64.77 50.8 0)
		(effects
			(font
				(size 1.27 1.27)
			)
			(justify left bottom)
		)
	)
	(label "USER_LED_B"
		(at 16.51 246.38 0)
		(effects
			(font
				(size 1.27 1.27)
			)
			(justify left bottom)
		)
	)
	(label "PI3HDX511F.SDA"
		(at 349.885 151.13 180)
		(effects
			(font
				(size 1.27 1.27)
			)
			(justify right bottom)
		)
	)
	(label "WiFi.DAT2"
		(at 172.085 261.62 180)
		(effects
			(font
				(size 1.27 1.27)
			)
			(justify right bottom)
		)
	)
	(label "PI3HDX511F.SCL"
		(at 349.885 153.67 180)
		(effects
			(font
				(size 1.27 1.27)
			)
			(justify right bottom)
		)
	)
	(label "HDMI_FPGA.TX2_P"
		(at 221.615 93.98 180)
		(effects
			(font
				(size 1.27 1.27)
			)
			(justify right bottom)
		)
	)
	(label "CAM0.D1_N"
		(at 64.77 55.88 0)
		(effects
			(font
				(size 1.27 1.27)
			)
			(justify left bottom)
		)
	)
	(label "Crosslink.CLK"
		(at 211.455 124.46 180)
		(effects
			(font
				(size 1.27 1.27)
			)
			(justify right bottom)
		)
	)
	(label "WiFi_CLK"
		(at 40.64 152.4 0)
		(effects
			(font
				(size 1.27 1.27)
			)
			(justify left bottom)
		)
	)
	(label "CAM0.C_N"
		(at 64.77 66.04 0)
		(effects
			(font
				(size 1.27 1.27)
			)
			(justify left bottom)
		)
	)
	(label "PF_ETH_PWDN_n"
		(at 290.83 224.79 0)
		(effects
			(font
				(size 1.27 1.27)
			)
			(justify left bottom)
		)
	)
	(label "HDMI_FPGA.CLK_P"
		(at 44.45 58.42 0)
		(effects
			(font
				(size 1.27 1.27)
			)
			(justify left bottom)
		)
	)
	(label "SDA0_PF"
		(at 187.96 55.88 180)
		(effects
			(font
				(size 1.27 1.27)
			)
			(justify right bottom)
		)
	)
	(label "HDMI0_HPD_SRC"
		(at 294.64 191.77 0)
		(effects
			(font
				(size 1.27 1.27)
			)
			(justify left bottom)
		)
	)
	(label "SCL0_PF"
		(at 187.96 53.34 180)
		(effects
			(font
				(size 1.27 1.27)
			)
			(justify right bottom)
		)
	)
	(label "Crosslink.SDA"
		(at 189.23 116.84 180)
		(effects
			(font
				(size 1.27 1.27)
			)
			(justify right bottom)
		)
	)
	(label "WiFi_DATA_2"
		(at 40.64 147.32 0)
		(effects
			(font
				(size 1.27 1.27)
			)
			(justify left bottom)
		)
	)
	(label "Crosslink.MISO"
		(at 211.455 127 180)
		(effects
			(font
				(size 1.27 1.27)
			)
			(justify right bottom)
		)
	)
	(label "HDMI_FPGA.TX0_P"
		(at 221.615 68.58 180)
		(effects
			(font
				(size 1.27 1.27)
			)
			(justify right bottom)
		)
	)
	(label "PF_ETH_PWDN_n"
		(at 59.69 78.74 0)
		(effects
			(font
				(size 1.27 1.27)
			)
			(justify left bottom)
		)
	)
	(label "WiFi_DATA_2"
		(at 119.38 261.62 0)
		(effects
			(font
				(size 1.27 1.27)
			)
			(justify left bottom)
		)
	)
	(label "HDMI0_SDA_SRC"
		(at 292.1 151.13 0)
		(effects
			(font
				(size 1.27 1.27)
			)
			(justify left bottom)
		)
	)
	(label "PF_ETH_RESET_n"
		(at 59.69 81.28 0)
		(effects
			(font
				(size 1.27 1.27)
			)
			(justify left bottom)
		)
	)
	(label "PCIe_nRST_PF"
		(at 288.29 119.38 0)
		(effects
			(font
				(size 1.27 1.27)
			)
			(justify left bottom)
		)
	)
	(label "USER_LED_B"
		(at 218.44 144.78 180)
		(effects
			(font
				(size 1.27 1.27)
			)
			(justify right bottom)
		)
	)
	(label "WiFi_DATA_3"
		(at 40.64 149.86 0)
		(effects
			(font
				(size 1.27 1.27)
			)
			(justify left bottom)
		)
	)
	(label "WiFi_DATA_1"
		(at 40.64 144.78 0)
		(effects
			(font
				(size 1.27 1.27)
			)
			(justify left bottom)
		)
	)
	(label "WiFi.DAT1"
		(at 172.085 209.55 180)
		(effects
			(font
				(size 1.27 1.27)
			)
			(justify right bottom)
		)
	)
	(label "Crosslink.MOSI"
		(at 211.455 119.38 180)
		(effects
			(font
				(size 1.27 1.27)
			)
			(justify right bottom)
		)
	)
	(label "ETH.MDC"
		(at 335.28 81.28 0)
		(effects
			(font
				(size 1.27 1.27)
			)
			(justify left bottom)
		)
	)
	(label "SCL0_PF"
		(at 297.18 54.61 0)
		(effects
			(font
				(size 1.27 1.27)
			)
			(justify left bottom)
		)
	)
	(label "CAM0.C_P"
		(at 64.77 63.5 0)
		(effects
			(font
				(size 1.27 1.27)
			)
			(justify left bottom)
		)
	)
	(label "HDMI_FPGA.TX1_N"
		(at 221.615 76.2 180)
		(effects
			(font
				(size 1.27 1.27)
			)
			(justify right bottom)
		)
	)
	(label "USER_LED_R"
		(at 73.66 246.38 0)
		(effects
			(font
				(size 1.27 1.27)
			)
			(justify left bottom)
		)
	)
	(label "HDMI_FPGA.TX0_N"
		(at 221.615 71.12 180)
		(effects
			(font
				(size 1.27 1.27)
			)
			(justify right bottom)
		)
	)
	(label "HDMI0_SCL_SRC"
		(at 292.1 153.67 0)
		(effects
			(font
				(size 1.27 1.27)
			)
			(justify left bottom)
		)
	)
	(label "PF_ETH_MDC"
		(at 59.69 73.66 0)
		(effects
			(font
				(size 1.27 1.27)
			)
			(justify left bottom)
		)
	)
	(label "WiFi.DAT3"
		(at 171.45 236.22 180)
		(effects
			(font
				(size 1.27 1.27)
			)
			(justify right bottom)
		)
	)
	(label "WiFi_DATA_0"
		(at 40.64 142.24 0)
		(effects
			(font
				(size 1.27 1.27)
			)
			(justify left bottom)
		)
	)
	(label "PF_ETH_MDC"
		(at 293.37 81.28 0)
		(effects
			(font
				(size 1.27 1.27)
			)
			(justify left bottom)
		)
	)
	(label "WiFi_CMD"
		(at 119.38 207.01 0)
		(effects
			(font
				(size 1.27 1.27)
			)
			(justify left bottom)
		)
	)
	(label "WiFi_CLK"
		(at 119.38 264.16 0)
		(effects
			(font
				(size 1.27 1.27)
			)
			(justify left bottom)
		)
	)
	(label "HDMI0_SDA_SRC"
		(at 185.42 99.06 180)
		(effects
			(font
				(size 1.27 1.27)
			)
			(justify right bottom)
		)
	)
	(label "I^{2}C0.SCL"
		(at 349.885 54.61 180)
		(effects
			(font
				(size 1.27 1.27)
			)
			(justify right bottom)
		)
	)
	(label "USER_LED_R"
		(at 218.44 139.7 180)
		(effects
			(font
				(size 1.27 1.27)
			)
			(justify right bottom)
		)
	)
	(label "PF_ETH_MDIO"
		(at 293.37 83.82 0)
		(effects
			(font
				(size 1.27 1.27)
			)
			(justify left bottom)
		)
	)
	(label "WiFi.CMD"
		(at 172.085 207.01 180)
		(effects
			(font
				(size 1.27 1.27)
			)
			(justify right bottom)
		)
	)
	(label "USER_LED_G"
		(at 218.44 142.24 180)
		(effects
			(font
				(size 1.27 1.27)
			)
			(justify right bottom)
		)
	)
	(label "PCIe_CLK_nREQ_PF"
		(at 288.29 116.84 0)
		(effects
			(font
				(size 1.27 1.27)
			)
			(justify left bottom)
		)
	)
	(global_label "GPIO24"
		(shape input)
		(at 71.12 132.08 180)
		(fields_autoplaced yes)
		(effects
			(font
				(size 1.27 1.27)
			)
			(justify right)
		)
		(property "Intersheetrefs" "${INTERSHEET_REFS}"
			(at 61.8126 132.0006 0)
			(effects
				(font
					(size 1.27 1.27)
				)
				(justify right)
			)
		)
	)
	(global_label "PCIe_CLK_nREQ"
		(shape input)
		(at 349.25 116.84 0)
		(fields_autoplaced yes)
		(effects
			(font
				(size 1.27 1.27)
			)
			(justify left)
		)
		(property "Intersheetrefs" "${INTERSHEET_REFS}"
			(at 366.8704 116.84 0)
			(effects
				(font
					(size 1.27 1.27)
				)
				(justify left)
			)
		)
	)
	(global_label "GPIO7"
		(shape input)
		(at 172.72 152.4 0)
		(fields_autoplaced yes)
		(effects
			(font
				(size 1.27 1.27)
			)
			(justify left)
		)
		(property "Intersheetrefs" "${INTERSHEET_REFS}"
			(at 180.8179 152.3206 0)
			(effects
				(font
					(size 1.27 1.27)
				)
				(justify left)
			)
		)
	)
	(global_label "UART0_TX{slash}RPI_GPIO14"
		(shape input)
		(at 172.72 88.9 0)
		(fields_autoplaced yes)
		(effects
			(font
				(size 1.27 1.27)
			)
			(justify left)
		)
		(property "Intersheetrefs" "${INTERSHEET_REFS}"
			(at 196.4812 88.8206 0)
			(effects
				(font
					(size 1.27 1.27)
				)
				(justify left)
			)
		)
	)
	(global_label "GPIO25"
		(shape input)
		(at 71.12 96.52 180)
		(fields_autoplaced yes)
		(effects
			(font
				(size 1.27 1.27)
			)
			(justify right)
		)
		(property "Intersheetrefs" "${INTERSHEET_REFS}"
			(at 61.8126 96.4406 0)
			(effects
				(font
					(size 1.27 1.27)
				)
				(justify right)
			)
		)
	)
	(global_label "SCL6{slash}RPI_GPIO23"
		(shape input)
		(at 71.12 106.68 180)
		(fields_autoplaced yes)
		(effects
			(font
				(size 1.27 1.27)
			)
			(justify right)
		)
		(property "Intersheetrefs" "${INTERSHEET_REFS}"
			(at 51.6526 106.6006 0)
			(effects
				(font
					(size 1.27 1.27)
				)
				(justify right)
			)
		)
	)
	(global_label "ETH_RESET_n"
		(shape input)
		(at 335.28 227.33 0)
		(fields_autoplaced yes)
		(effects
			(font
				(size 1.27 1.27)
			)
			(justify left)
		)
		(property "Intersheetrefs" "${INTERSHEET_REFS}"
			(at 349.9698 227.2506 0)
			(effects
				(font
					(size 1.27 1.27)
				)
				(justify left)
			)
		)
	)
	(global_label "GPIO10"
		(shape input)
		(at 71.12 119.38 180)
		(fields_autoplaced yes)
		(effects
			(font
				(size 1.27 1.27)
			)
			(justify right)
		)
		(property "Intersheetrefs" "${INTERSHEET_REFS}"
			(at 61.8126 119.3006 0)
			(effects
				(font
					(size 1.27 1.27)
				)
				(justify right)
			)
		)
	)
	(global_label "VREF_FLAG"
		(shape input)
		(at 172.72 86.36 0)
		(fields_autoplaced yes)
		(effects
			(font
				(size 1.27 1.27)
			)
			(justify left)
		)
		(property "Intersheetrefs" "${INTERSHEET_REFS}"
			(at 185.7443 86.36 0)
			(effects
				(font
					(size 1.27 1.27)
				)
				(justify left)
			)
		)
	)
	(global_label "SDA6{slash}RPI_GPIO22"
		(shape input)
		(at 172.72 132.08 0)
		(fields_autoplaced yes)
		(effects
			(font
				(size 1.27 1.27)
			)
			(justify left)
		)
		(property "Intersheetrefs" "${INTERSHEET_REFS}"
			(at 192.2479 132.0006 0)
			(effects
				(font
					(size 1.27 1.27)
				)
				(justify left)
			)
		)
	)
	(global_label "UART3_RX{slash}RPI_GPIO05"
		(shape input)
		(at 71.12 114.3 180)
		(fields_autoplaced yes)
		(effects
			(font
				(size 1.27 1.27)
			)
			(justify right)
		)
		(property "Intersheetrefs" "${INTERSHEET_REFS}"
			(at 47.0564 114.2206 0)
			(effects
				(font
					(size 1.27 1.27)
				)
				(justify right)
			)
		)
	)
	(global_label "SPI6_CEO_N{slash}RPI_GPIO18"
		(shape input)
		(at 71.12 83.82 180)
		(fields_autoplaced yes)
		(effects
			(font
				(size 1.27 1.27)
			)
			(justify right)
		)
		(property "Intersheetrefs" "${INTERSHEET_REFS}"
			(at 45.0607 83.7406 0)
			(effects
				(font
					(size 1.27 1.27)
				)
				(justify right)
			)
		)
	)
	(global_label "GPIO26"
		(shape input)
		(at 71.12 134.62 180)
		(fields_autoplaced yes)
		(effects
			(font
				(size 1.27 1.27)
			)
			(justify right)
		)
		(property "Intersheetrefs" "${INTERSHEET_REFS}"
			(at 61.8126 134.5406 0)
			(effects
				(font
					(size 1.27 1.27)
				)
				(justify right)
			)
		)
	)
	(global_label "UART5_TX{slash}RPI_GPIO12"
		(shape input)
		(at 71.12 121.92 180)
		(fields_autoplaced yes)
		(effects
			(font
				(size 1.27 1.27)
			)
			(justify right)
		)
		(property "Intersheetrefs" "${INTERSHEET_REFS}"
			(at 47.3588 121.8406 0)
			(effects
				(font
					(size 1.27 1.27)
				)
				(justify right)
			)
		)
	)
	(global_label "UART3_TX{slash}RPI_GPIO04"
		(shape input)
		(at 172.72 83.82 0)
		(fields_autoplaced yes)
		(effects
			(font
				(size 1.27 1.27)
			)
			(justify left)
		)
		(property "Intersheetrefs" "${INTERSHEET_REFS}"
			(at 197.0533 83.82 0)
			(effects
				(font
					(size 1.27 1.27)
				)
				(justify left)
			)
		)
	)
	(global_label "GPIO6"
		(shape input)
		(at 71.12 116.84 180)
		(fields_autoplaced yes)
		(effects
			(font
				(size 1.27 1.27)
			)
			(justify right)
		)
		(property "Intersheetrefs" "${INTERSHEET_REFS}"
			(at 63.0221 116.7606 0)
			(effects
				(font
					(size 1.27 1.27)
				)
				(justify right)
			)
		)
	)
	(global_label "UART0_RX{slash}RPI_GPIO15"
		(shape input)
		(at 71.12 86.36 180)
		(fields_autoplaced yes)
		(effects
			(font
				(size 1.27 1.27)
			)
			(justify right)
		)
		(property "Intersheetrefs" "${INTERSHEET_REFS}"
			(at 47.0564 86.2806 0)
			(effects
				(font
					(size 1.27 1.27)
				)
				(justify right)
			)
		)
	)
	(global_label "SPI6_MOSI{slash}RPI_GPIO20"
		(shape input)
		(at 71.12 127 180)
		(fields_autoplaced yes)
		(effects
			(font
				(size 1.27 1.27)
			)
			(justify right)
		)
		(property "Intersheetrefs" "${INTERSHEET_REFS}"
			(at 46.5121 126.9206 0)
			(effects
				(font
					(size 1.27 1.27)
				)
				(justify right)
			)
		)
	)
	(global_label "SPI6_MISO{slash}RPI_GPIO19"
		(shape input)
		(at 71.12 124.46 180)
		(fields_autoplaced yes)
		(effects
			(font
				(size 1.27 1.27)
			)
			(justify right)
		)
		(property "Intersheetrefs" "${INTERSHEET_REFS}"
			(at 46.5121 124.3806 0)
			(effects
				(font
					(size 1.27 1.27)
				)
				(justify right)
			)
		)
	)
	(global_label "~{Crosslink_RESET}"
		(shape input)
		(at 71.12 99.06 180)
		(fields_autoplaced yes)
		(effects
			(font
				(size 1.27 1.27)
			)
			(justify right)
		)
		(property "Intersheetrefs" "${INTERSHEET_REFS}"
			(at 52.7136 99.06 0)
			(effects
				(font
					(size 1.27 1.27)
				)
				(justify right)
			)
		)
	)
	(global_label "SPI6_SCLK{slash}RPI_GPIO21"
		(shape input)
		(at 71.12 129.54 180)
		(fields_autoplaced yes)
		(effects
			(font
				(size 1.27 1.27)
			)
			(justify right)
		)
		(property "Intersheetrefs" "${INTERSHEET_REFS}"
			(at 46.3307 129.4606 0)
			(effects
				(font
					(size 1.27 1.27)
				)
				(justify right)
			)
		)
	)
	(global_label "SDA1{slash}RPI_GPIO02"
		(shape input)
		(at 71.12 109.22 180)
		(fields_autoplaced yes)
		(effects
			(font
				(size 1.27 1.27)
			)
			(justify right)
		)
		(property "Intersheetrefs" "${INTERSHEET_REFS}"
			(at 51.5921 109.1406 0)
			(effects
				(font
					(size 1.27 1.27)
				)
				(justify right)
			)
		)
	)
	(global_label "GPIO27"
		(shape input)
		(at 71.12 137.16 180)
		(fields_autoplaced yes)
		(effects
			(font
				(size 1.27 1.27)
			)
			(justify right)
		)
		(property "Intersheetrefs" "${INTERSHEET_REFS}"
			(at 61.8126 137.0806 0)
			(effects
				(font
					(size 1.27 1.27)
				)
				(justify right)
			)
		)
	)
	(global_label "PI3HDX511F_HOTPLUG"
		(shape input)
		(at 331.47 191.77 0)
		(fields_autoplaced yes)
		(effects
			(font
				(size 1.27 1.27)
			)
			(justify left)
		)
		(property "Intersheetrefs" "${INTERSHEET_REFS}"
			(at 355.5614 191.77 0)
			(effects
				(font
					(size 1.27 1.27)
				)
				(justify left)
			)
		)
	)
	(global_label "UART4_TX{slash}RPI_GPIO08"
		(shape input)
		(at 172.72 134.62 0)
		(fields_autoplaced yes)
		(effects
			(font
				(size 1.27 1.27)
			)
			(justify left)
		)
		(property "Intersheetrefs" "${INTERSHEET_REFS}"
			(at 196.4812 134.5406 0)
			(effects
				(font
					(size 1.27 1.27)
				)
				(justify left)
			)
		)
	)
	(global_label "UART4_RX{slash}RPI_GPIO09"
		(shape input)
		(at 172.72 137.16 0)
		(fields_autoplaced yes)
		(effects
			(font
				(size 1.27 1.27)
			)
			(justify left)
		)
		(property "Intersheetrefs" "${INTERSHEET_REFS}"
			(at 196.7836 137.0806 0)
			(effects
				(font
					(size 1.27 1.27)
				)
				(justify left)
			)
		)
	)
	(global_label "SCL1{slash}RPI_GPIO03"
		(shape input)
		(at 71.12 111.76 180)
		(fields_autoplaced yes)
		(effects
			(font
				(size 1.27 1.27)
			)
			(justify right)
		)
		(property "Intersheetrefs" "${INTERSHEET_REFS}"
			(at 51.6526 111.6806 0)
			(effects
				(font
					(size 1.27 1.27)
				)
				(justify right)
			)
		)
	)
	(global_label "GPIO11"
		(shape input)
		(at 187.96 104.14 0)
		(fields_autoplaced yes)
		(effects
			(font
				(size 1.27 1.27)
			)
			(justify left)
		)
		(property "Intersheetrefs" "${INTERSHEET_REFS}"
			(at 197.2674 104.0606 0)
			(effects
				(font
					(size 1.27 1.27)
				)
				(justify left)
			)
		)
	)
	(global_label "GPIO17"
		(shape input)
		(at 71.12 91.44 180)
		(fields_autoplaced yes)
		(effects
			(font
				(size 1.27 1.27)
			)
			(justify right)
		)
		(property "Intersheetrefs" "${INTERSHEET_REFS}"
			(at 61.8126 91.3606 0)
			(effects
				(font
					(size 1.27 1.27)
				)
				(justify right)
			)
		)
	)
	(global_label "ETH_PWDN_n"
		(shape input)
		(at 335.28 224.79 0)
		(fields_autoplaced yes)
		(effects
			(font
				(size 1.27 1.27)
			)
			(justify left)
		)
		(property "Intersheetrefs" "${INTERSHEET_REFS}"
			(at 349.5464 224.7106 0)
			(effects
				(font
					(size 1.27 1.27)
				)
				(justify left)
			)
		)
	)
	(global_label "UART5_TX{slash}RPI_GPIO13"
		(shape input)
		(at 172.72 66.04 0)
		(fields_autoplaced yes)
		(effects
			(font
				(size 1.27 1.27)
			)
			(justify left)
		)
		(property "Intersheetrefs" "${INTERSHEET_REFS}"
			(at 197.0533 66.04 0)
			(effects
				(font
					(size 1.27 1.27)
				)
				(justify left)
			)
		)
	)
	(global_label "PCIe_nRST"
		(shape input)
		(at 349.25 119.38 0)
		(fields_autoplaced yes)
		(effects
			(font
				(size 1.27 1.27)
			)
			(justify left)
		)
		(property "Intersheetrefs" "${INTERSHEET_REFS}"
			(at 362.0323 119.38 0)
			(effects
				(font
					(size 1.27 1.27)
				)
				(justify left)
			)
		)
	)
	(global_label "GPIO16"
		(shape input)
		(at 172.72 78.74 0)
		(fields_autoplaced yes)
		(effects
			(font
				(size 1.27 1.27)
			)
			(justify left)
		)
		(property "Intersheetrefs" "${INTERSHEET_REFS}"
			(at 182.0274 78.6606 0)
			(effects
				(font
					(size 1.27 1.27)
				)
				(justify left)
			)
		)
	)
	(hierarchical_label "Crosslink{I^{2}C}"
		(shape bidirectional)
		(at 193.04 113.03 0)
		(effects
			(font
				(size 1.27 1.27)
			)
			(justify left)
		)
	)
	(hierarchical_label "PI3HDX511F{I^{2}C}"
		(shape bidirectional)
		(at 355.6 146.05 0)
		(effects
			(font
				(size 1.27 1.27)
			)
			(justify left)
		)
	)
	(hierarchical_label "HDMI_FPGA{HDMI}"
		(shape bidirectional)
		(at 40.64 54.61 180)
		(effects
			(font
				(size 1.27 1.27)
			)
			(justify right)
		)
	)
	(hierarchical_label "ULPI{ULPI}"
		(shape input)
		(at 193.04 55.88 0)
		(effects
			(font
				(size 1.27 1.27)
			)
			(justify left)
		)
	)
	(hierarchical_label "ETH{SMI}"
		(shape input)
		(at 355.6 76.2 0)
		(effects
			(font
				(size 1.27 1.27)
			)
			(justify left)
		)
	)
	(hierarchical_label "Crosslink{SPI}"
		(shape bidirectional)
		(at 217.17 114.3 0)
		(effects
			(font
				(size 1.27 1.27)
			)
			(justify left)
		)
	)
	(hierarchical_label "HDMI_FPGA{HDMI}"
		(shape bidirectional)
		(at 231.14 63.5 0)
		(effects
			(font
				(size 1.27 1.27)
			)
			(justify left)
		)
	)
	(hierarchical_label "WiFi{SDIO}"
		(shape input)
		(at 177.8 201.93 0)
		(effects
			(font
				(size 1.27 1.27)
			)
			(justify left)
		)
	)
	(hierarchical_label "CAM0{CSI}"
		(shape bidirectional)
		(at 59.69 44.45 180)
		(effects
			(font
				(size 1.27 1.27)
			)
			(justify right)
		)
	)
	(hierarchical_label "I^{2}C0{I^{2}C}"
		(shape input)
		(at 355.6 49.53 0)
		(effects
			(font
				(size 1.27 1.27)
			)
			(justify left)
		)
	)
	(symbol
		(lib_id "antmicroResistors0402:R_470R_0402")
		(at 66.04 232.41 90)
		(unit 1)
		(exclude_from_sim no)
		(in_bom yes)
		(on_board yes)
		(dnp no)
		(fields_autoplaced yes)
		(property "Reference" "R71"
			(at 68.58 228.6 90)
			(effects
				(font
					(size 1.27 1.27)
					(thickness 0.15)
				)
				(justify right)
			)
		)
		(property "Value" "R_470R_0402"
			(at 78.74 212.09 0)
			(effects
				(font
					(size 1.27 1.27)
					(thickness 0.15)
				)
				(justify left bottom)
				(hide yes)
			)
		)
		(property "Footprint" "antmicro-footprints:R_0402_1005Metric"
			(at 81.28 212.09 0)
			(effects
				(font
					(size 1.27 1.27)
					(thickness 0.15)
				)
				(justify left bottom)
				(hide yes)
			)
		)
		(property "Datasheet" "https://www.bourns.com/docs/product-datasheets/cr.pdf"
			(at 83.82 212.09 0)
			(effects
				(font
					(size 1.27 1.27)
					(thickness 0.15)
				)
				(justify left bottom)
				(hide yes)
			)
		)
		(property "Description" "SMD Chip Resistor, 470 ohm, ± 1%, 62.5 mW, 0402 [1005 Metric], Thick Film, General Purpose"
			(at 66.04 232.41 0)
			(effects
				(font
					(size 1.27 1.27)
				)
				(hide yes)
			)
		)
		(property "MPN" "CR0402-FX-4700GLF"
			(at 86.36 212.09 0)
			(effects
				(font
					(size 1.27 1.27)
					(thickness 0.15)
				)
				(justify left bottom)
				(hide yes)
			)
		)
		(property "Manufacturer" "Bourns"
			(at 88.9 212.09 0)
			(effects
				(font
					(size 1.27 1.27)
					(thickness 0.15)
				)
				(justify left bottom)
				(hide yes)
			)
		)
		(property "License" "Apache-2.0"
			(at 91.44 212.09 0)
			(effects
				(font
					(size 1.27 1.27)
					(thickness 0.15)
				)
				(justify left bottom)
				(hide yes)
			)
		)
		(property "Author" "Antmicro"
			(at 93.98 212.09 0)
			(effects
				(font
					(size 1.27 1.27)
					(thickness 0.15)
				)
				(justify left bottom)
				(hide yes)
			)
		)
		(property "Val" "470R"
			(at 68.58 231.14 90)
			(effects
				(font
					(size 1.27 1.27)
					(thickness 0.15)
				)
				(justify right)
			)
		)
		(property "Tolerance" "1%"
			(at 76.2 212.09 0)
			(effects
				(font
					(size 1.27 1.27)
				)
				(justify left bottom)
				(hide yes)
			)
		)
		(property "Public" ""
			(at 96.52 212.09 0)
			(effects
				(font
					(size 1.27 1.27)
				)
				(justify left bottom)
				(hide yes)
			)
		)
		(pin "2"
		)
		(pin "1"
		)
		(instances
			(project "polarfire-som"
				(path ""
					(reference "R71")
					(unit 1)
				)
			)
		)
	)
	(symbol
		(lib_id "antmicroCapacitors0402:C_100n_0402")
		(at 335.28 40.64 270)
		(unit 1)
		(exclude_from_sim no)
		(in_bom yes)
		(on_board yes)
		(dnp no)
		(property "Reference" "C131"
			(at 339.09 40.64 90)
			(effects
				(font
					(size 1.27 1.27)
					(thickness 0.15)
				)
			)
		)
		(property "Value" "C_100n_0402"
			(at 325.12 60.96 0)
			(effects
				(font
					(size 1.27 1.27)
					(thickness 0.15)
				)
				(justify left bottom)
				(hide yes)
			)
		)
		(property "Footprint" "antmicro-footprints:C_0402_1005Metric"
			(at 322.58 60.96 0)
			(effects
				(font
					(size 1.27 1.27)
					(thickness 0.15)
				)
				(justify left bottom)
				(hide yes)
			)
		)
		(property "Datasheet" "https://www.murata.com/products/productdetail?partno=GRM155R61H104KE14%23"
			(at 320.04 60.96 0)
			(effects
				(font
					(size 1.27 1.27)
					(thickness 0.15)
				)
				(justify left bottom)
				(hide yes)
			)
		)
		(property "Description" "SMD Multilayer Ceramic Capacitor, 0.1 µF, 50 V, 0402 [1005 Metric], ± 10%, X5R, GRM Series"
			(at 335.28 40.64 0)
			(effects
				(font
					(size 1.27 1.27)
				)
				(hide yes)
			)
		)
		(property "MPN" "GRM155R61H104KE14D"
			(at 317.5 60.96 0)
			(effects
				(font
					(size 1.27 1.27)
					(thickness 0.15)
				)
				(justify left bottom)
				(hide yes)
			)
		)
		(property "Manufacturer" "Murata"
			(at 314.96 60.96 0)
			(effects
				(font
					(size 1.27 1.27)
					(thickness 0.15)
				)
				(justify left bottom)
				(hide yes)
			)
		)
		(property "License" "Apache-2.0"
			(at 312.42 60.96 0)
			(effects
				(font
					(size 1.27 1.27)
					(thickness 0.15)
				)
				(justify left bottom)
				(hide yes)
			)
		)
		(property "Author" "Antmicro"
			(at 309.88 60.96 0)
			(effects
				(font
					(size 1.27 1.27)
					(thickness 0.15)
				)
				(justify left bottom)
				(hide yes)
			)
		)
		(property "Val" "100n"
			(at 336.55 45.72 90)
			(effects
				(font
					(size 1.27 1.27)
					(thickness 0.15)
				)
				(justify left bottom)
			)
		)
		(property "Voltage" "50V"
			(at 307.34 60.96 0)
			(effects
				(font
					(size 1.27 1.27)
				)
				(justify left bottom)
				(hide yes)
			)
		)
		(property "Dielectric" "X5R"
			(at 304.8 60.96 0)
			(effects
				(font
					(size 1.27 1.27)
				)
				(justify left bottom)
				(hide yes)
			)
		)
		(property "Public" ""
			(at 302.26 60.96 0)
			(effects
				(font
					(size 1.27 1.27)
				)
				(justify left bottom)
				(hide yes)
			)
		)
		(pin "2"
		)
		(pin "1"
		)
		(instances
			(project "polarfire-som"
				(path ""
					(reference "C131")
					(unit 1)
				)
			)
		)
	)
	(symbol
		(lib_id "antmicropower:GND")
		(at 36.83 255.27 0)
		(unit 1)
		(exclude_from_sim no)
		(in_bom yes)
		(on_board yes)
		(dnp no)
		(property "Reference" "#PWR0286"
			(at 45.72 257.81 0)
			(effects
				(font
					(size 1.27 1.27)
					(thickness 0.15)
				)
				(justify left bottom)
				(hide yes)
			)
		)
		(property "Value" "GND"
			(at 36.83 259.08 0)
			(effects
				(font
					(size 1.27 1.27)
					(thickness 0.15)
				)
			)
		)
		(property "Footprint" ""
			(at 45.72 262.89 0)
			(effects
				(font
					(size 1.27 1.27)
					(thickness 0.15)
				)
				(justify left bottom)
				(hide yes)
			)
		)
		(property "Datasheet" ""
			(at 45.72 267.97 0)
			(effects
				(font
					(size 1.27 1.27)
					(thickness 0.15)
				)
				(justify left bottom)
				(hide yes)
			)
		)
		(property "Description" ""
			(at 36.83 255.27 0)
			(effects
				(font
					(size 1.27 1.27)
				)
				(hide yes)
			)
		)
		(property "Author" "Antmicro"
			(at 45.72 262.89 0)
			(effects
				(font
					(size 1.27 1.27)
					(thickness 0.15)
				)
				(justify left bottom)
				(hide yes)
			)
		)
		(property "License" "Apache-2.0"
			(at 45.72 265.43 0)
			(effects
				(font
					(size 1.27 1.27)
					(thickness 0.15)
				)
				(justify left bottom)
				(hide yes)
			)
		)
		(pin "1"
		)
		(instances
			(project "polarfire-som"
				(path ""
					(reference "#PWR0286")
					(unit 1)
				)
			)
		)
	)
	(symbol
		(lib_id "antmicropower:GND")
		(at 193.04 233.68 0)
		(unit 1)
		(exclude_from_sim no)
		(in_bom yes)
		(on_board yes)
		(dnp no)
		(property "Reference" "#PWR0346"
			(at 201.93 236.22 0)
			(effects
				(font
					(size 1.27 1.27)
					(thickness 0.15)
				)
				(justify left bottom)
				(hide yes)
			)
		)
		(property "Value" "GND"
			(at 196.85 234.95 0)
			(effects
				(font
					(size 1.27 1.27)
					(thickness 0.15)
				)
			)
		)
		(property "Footprint" ""
			(at 201.93 241.3 0)
			(effects
				(font
					(size 1.27 1.27)
					(thickness 0.15)
				)
				(justify left bottom)
				(hide yes)
			)
		)
		(property "Datasheet" ""
			(at 201.93 246.38 0)
			(effects
				(font
					(size 1.27 1.27)
					(thickness 0.15)
				)
				(justify left bottom)
				(hide yes)
			)
		)
		(property "Description" ""
			(at 193.04 233.68 0)
			(effects
				(font
					(size 1.27 1.27)
				)
				(hide yes)
			)
		)
		(property "Author" "Antmicro"
			(at 201.93 241.3 0)
			(effects
				(font
					(size 1.27 1.27)
					(thickness 0.15)
				)
				(justify left bottom)
				(hide yes)
			)
		)
		(property "License" "Apache-2.0"
			(at 201.93 243.84 0)
			(effects
				(font
					(size 1.27 1.27)
					(thickness 0.15)
				)
				(justify left bottom)
				(hide yes)
			)
		)
		(pin "1"
		)
		(instances
			(project "polarfire-som"
				(path ""
					(reference "#PWR0346")
					(unit 1)
				)
			)
		)
	)
	(symbol
		(lib_id "antmicropower:GND")
		(at 334.01 232.41 0)
		(mirror y)
		(unit 1)
		(exclude_from_sim no)
		(in_bom yes)
		(on_board yes)
		(dnp no)
		(property "Reference" "#PWR0305"
			(at 325.12 234.95 0)
			(effects
				(font
					(size 1.27 1.27)
					(thickness 0.15)
				)
				(justify left bottom)
				(hide yes)
			)
		)
		(property "Value" "GND"
			(at 334.01 236.22 0)
			(effects
				(font
					(size 1.27 1.27)
					(thickness 0.15)
				)
			)
		)
		(property "Footprint" ""
			(at 325.12 240.03 0)
			(effects
				(font
					(size 1.27 1.27)
					(thickness 0.15)
				)
				(justify left bottom)
				(hide yes)
			)
		)
		(property "Datasheet" ""
			(at 325.12 245.11 0)
			(effects
				(font
					(size 1.27 1.27)
					(thickness 0.15)
				)
				(justify left bottom)
				(hide yes)
			)
		)
		(property "Description" ""
			(at 334.01 232.41 0)
			(effects
				(font
					(size 1.27 1.27)
				)
				(hide yes)
			)
		)
		(property "Author" "Antmicro"
			(at 325.12 240.03 0)
			(effects
				(font
					(size 1.27 1.27)
					(thickness 0.15)
				)
				(justify left bottom)
				(hide yes)
			)
		)
		(property "License" "Apache-2.0"
			(at 325.12 242.57 0)
			(effects
				(font
					(size 1.27 1.27)
					(thickness 0.15)
				)
				(justify left bottom)
				(hide yes)
			)
		)
		(pin "1"
		)
		(instances
			(project "polarfire-som"
				(path ""
					(reference "#PWR0305")
					(unit 1)
				)
			)
		)
	)
	(symbol
		(lib_id "antmicropower:VDDI")
		(at 373.38 78.74 0)
		(unit 1)
		(exclude_from_sim no)
		(in_bom yes)
		(on_board yes)
		(dnp no)
		(fields_autoplaced yes)
		(property "Reference" "#PWR0248"
			(at 373.38 82.55 0)
			(effects
				(font
					(size 1.27 1.27)
				)
				(hide yes)
			)
		)
		(property "Value" "VDD"
			(at 373.38 74.295 0)
			(effects
				(font
					(size 1.27 1.27)
				)
			)
		)
		(property "Footprint" ""
			(at 373.38 78.74 0)
			(effects
				(font
					(size 1.27 1.27)
				)
				(hide yes)
			)
		)
		(property "Datasheet" ""
			(at 373.38 78.74 0)
			(effects
				(font
					(size 1.27 1.27)
				)
				(hide yes)
			)
		)
		(property "Description" ""
			(at 373.38 78.74 0)
			(effects
				(font
					(size 1.27 1.27)
				)
				(hide yes)
			)
		)
		(pin "1"
		)
		(instances
			(project "polarfire-som"
				(path ""
					(reference "#PWR0248")
					(unit 1)
				)
			)
		)
	)
	(symbol
		(lib_id "antmicropower:VDDI")
		(at 311.15 187.96 0)
		(mirror y)
		(unit 1)
		(exclude_from_sim no)
		(in_bom yes)
		(on_board yes)
		(dnp no)
		(fields_autoplaced yes)
		(property "Reference" "#PWR0162"
			(at 311.15 191.77 0)
			(effects
				(font
					(size 1.27 1.27)
				)
				(hide yes)
			)
		)
		(property "Value" "VDD"
			(at 311.15 182.88 0)
			(effects
				(font
					(size 1.27 1.27)
				)
			)
		)
		(property "Footprint" ""
			(at 311.15 187.96 0)
			(effects
				(font
					(size 1.27 1.27)
				)
				(hide yes)
			)
		)
		(property "Datasheet" ""
			(at 311.15 187.96 0)
			(effects
				(font
					(size 1.27 1.27)
				)
				(hide yes)
			)
		)
		(property "Description" ""
			(at 311.15 187.96 0)
			(effects
				(font
					(size 1.27 1.27)
				)
				(hide yes)
			)
		)
		(pin "1"
		)
		(instances
			(project "polarfire-som"
				(path ""
					(reference "#PWR0162")
					(unit 1)
				)
			)
		)
	)
	(symbol
		(lib_id "antmicropower:GND")
		(at 156.21 267.97 0)
		(mirror y)
		(unit 1)
		(exclude_from_sim no)
		(in_bom yes)
		(on_board yes)
		(dnp no)
		(fields_autoplaced yes)
		(property "Reference" "#PWR0313"
			(at 147.32 270.51 0)
			(effects
				(font
					(size 1.27 1.27)
					(thickness 0.15)
				)
				(justify left bottom)
				(hide yes)
			)
		)
		(property "Value" "GND"
			(at 156.21 273.05 0)
			(effects
				(font
					(size 1.27 1.27)
					(thickness 0.15)
				)
			)
		)
		(property "Footprint" ""
			(at 147.32 275.59 0)
			(effects
				(font
					(size 1.27 1.27)
					(thickness 0.15)
				)
				(justify left bottom)
				(hide yes)
			)
		)
		(property "Datasheet" ""
			(at 147.32 280.67 0)
			(effects
				(font
					(size 1.27 1.27)
					(thickness 0.15)
				)
				(justify left bottom)
				(hide yes)
			)
		)
		(property "Description" ""
			(at 156.21 267.97 0)
			(effects
				(font
					(size 1.27 1.27)
				)
				(hide yes)
			)
		)
		(property "Author" "Antmicro"
			(at 147.32 275.59 0)
			(effects
				(font
					(size 1.27 1.27)
					(thickness 0.15)
				)
				(justify left bottom)
				(hide yes)
			)
		)
		(property "License" "Apache-2.0"
			(at 147.32 278.13 0)
			(effects
				(font
					(size 1.27 1.27)
					(thickness 0.15)
				)
				(justify left bottom)
				(hide yes)
			)
		)
		(pin "1"
		)
		(instances
			(project "polarfire-som"
				(path ""
					(reference "#PWR0313")
					(unit 1)
				)
			)
		)
	)
	(symbol
		(lib_id "antmicroLogicTranslatorsLevelShifters:NTS0102_XSON")
		(at 311.15 148.59 0)
		(unit 1)
		(exclude_from_sim no)
		(in_bom yes)
		(on_board yes)
		(dnp no)
		(fields_autoplaced yes)
		(property "Reference" "U14"
			(at 321.31 140.97 0)
			(effects
				(font
					(size 1.27 1.27)
					(thickness 0.15)
				)
			)
		)
		(property "Value" "NTS0102_XSON"
			(at 346.71 156.21 0)
			(effects
				(font
					(size 1.27 1.27)
					(thickness 0.15)
				)
				(justify left bottom)
				(hide yes)
			)
		)
		(property "Footprint" "antmicro-footprints:XSON-8_1x1.95mm_P0.5mm"
			(at 346.71 158.75 0)
			(effects
				(font
					(size 1.27 1.27)
					(thickness 0.15)
				)
				(justify left bottom)
				(hide yes)
			)
		)
		(property "Datasheet" "http://www.farnell.com/datasheets/1760723.pdf"
			(at 346.71 161.29 0)
			(effects
				(font
					(size 1.27 1.27)
					(thickness 0.15)
				)
				(justify left bottom)
				(hide yes)
			)
		)
		(property "Description" "Transceiver, 1.65 V to 3.6 V, XSON-8"
			(at 311.15 148.59 0)
			(effects
				(font
					(size 1.27 1.27)
				)
				(hide yes)
			)
		)
		(property "MPN" "NTS0102GT"
			(at 321.31 143.51 0)
			(effects
				(font
					(size 1.27 1.27)
					(thickness 0.15)
				)
			)
		)
		(property "Manufacturer" "NXP"
			(at 346.71 163.83 0)
			(effects
				(font
					(size 1.27 1.27)
					(thickness 0.15)
				)
				(justify left bottom)
				(hide yes)
			)
		)
		(property "Author" "Antmicro"
			(at 346.71 166.37 0)
			(effects
				(font
					(size 1.27 1.27)
					(thickness 0.15)
				)
				(justify left bottom)
				(hide yes)
			)
		)
		(property "License" "Apache-2.0"
			(at 346.71 168.91 0)
			(effects
				(font
					(size 1.27 1.27)
					(thickness 0.15)
				)
				(justify left bottom)
				(hide yes)
			)
		)
		(pin "2"
		)
		(pin "6"
		)
		(pin "7"
		)
		(pin "5"
		)
		(pin "4"
		)
		(pin "3"
		)
		(pin "1"
		)
		(pin "8"
		)
		(instances
			(project "polarfire-som"
				(path ""
					(reference "U14")
					(unit 1)
				)
			)
		)
	)
	(symbol
		(lib_id "antmicroCapacitors0402:C_100n_0402")
		(at 373.38 80.01 270)
		(unit 1)
		(exclude_from_sim no)
		(in_bom yes)
		(on_board yes)
		(dnp no)
		(property "Reference" "C18"
			(at 377.19 80.01 90)
			(effects
				(font
					(size 1.27 1.27)
					(thickness 0.15)
				)
			)
		)
		(property "Value" "C_100n_0402"
			(at 363.22 100.33 0)
			(effects
				(font
					(size 1.27 1.27)
					(thickness 0.15)
				)
				(justify left bottom)
				(hide yes)
			)
		)
		(property "Footprint" "antmicro-footprints:C_0402_1005Metric"
			(at 360.68 100.33 0)
			(effects
				(font
					(size 1.27 1.27)
					(thickness 0.15)
				)
				(justify left bottom)
				(hide yes)
			)
		)
		(property "Datasheet" "https://www.murata.com/products/productdetail?partno=GRM155R61H104KE14%23"
			(at 358.14 100.33 0)
			(effects
				(font
					(size 1.27 1.27)
					(thickness 0.15)
				)
				(justify left bottom)
				(hide yes)
			)
		)
		(property "Description" "SMD Multilayer Ceramic Capacitor, 0.1 µF, 50 V, 0402 [1005 Metric], ± 10%, X5R, GRM Series"
			(at 373.38 80.01 0)
			(effects
				(font
					(size 1.27 1.27)
				)
				(hide yes)
			)
		)
		(property "MPN" "GRM155R61H104KE14D"
			(at 355.6 100.33 0)
			(effects
				(font
					(size 1.27 1.27)
					(thickness 0.15)
				)
				(justify left bottom)
				(hide yes)
			)
		)
		(property "Manufacturer" "Murata"
			(at 353.06 100.33 0)
			(effects
				(font
					(size 1.27 1.27)
					(thickness 0.15)
				)
				(justify left bottom)
				(hide yes)
			)
		)
		(property "License" "Apache-2.0"
			(at 350.52 100.33 0)
			(effects
				(font
					(size 1.27 1.27)
					(thickness 0.15)
				)
				(justify left bottom)
				(hide yes)
			)
		)
		(property "Author" "Antmicro"
			(at 347.98 100.33 0)
			(effects
				(font
					(size 1.27 1.27)
					(thickness 0.15)
				)
				(justify left bottom)
				(hide yes)
			)
		)
		(property "Val" "100n"
			(at 374.65 85.09 90)
			(effects
				(font
					(size 1.27 1.27)
					(thickness 0.15)
				)
				(justify left bottom)
			)
		)
		(property "Voltage" "50V"
			(at 345.44 100.33 0)
			(effects
				(font
					(size 1.27 1.27)
				)
				(justify left bottom)
				(hide yes)
			)
		)
		(property "Dielectric" "X5R"
			(at 342.9 100.33 0)
			(effects
				(font
					(size 1.27 1.27)
				)
				(justify left bottom)
				(hide yes)
			)
		)
		(property "Public" ""
			(at 340.36 100.33 0)
			(effects
				(font
					(size 1.27 1.27)
				)
				(justify left bottom)
				(hide yes)
			)
		)
		(pin "2"
		)
		(pin "1"
		)
		(instances
			(project "polarfire-som"
				(path ""
					(reference "C18")
					(unit 1)
				)
			)
		)
	)
	(symbol
		(lib_id "antmicroCapacitors0402:C_100n_0402")
		(at 383.54 80.01 270)
		(unit 1)
		(exclude_from_sim no)
		(in_bom yes)
		(on_board yes)
		(dnp no)
		(property "Reference" "C19"
			(at 387.35 80.01 90)
			(effects
				(font
					(size 1.27 1.27)
					(thickness 0.15)
				)
			)
		)
		(property "Value" "C_100n_0402"
			(at 373.38 100.33 0)
			(effects
				(font
					(size 1.27 1.27)
					(thickness 0.15)
				)
				(justify left bottom)
				(hide yes)
			)
		)
		(property "Footprint" "antmicro-footprints:C_0402_1005Metric"
			(at 370.84 100.33 0)
			(effects
				(font
					(size 1.27 1.27)
					(thickness 0.15)
				)
				(justify left bottom)
				(hide yes)
			)
		)
		(property "Datasheet" "https://www.murata.com/products/productdetail?partno=GRM155R61H104KE14%23"
			(at 368.3 100.33 0)
			(effects
				(font
					(size 1.27 1.27)
					(thickness 0.15)
				)
				(justify left bottom)
				(hide yes)
			)
		)
		(property "Description" "SMD Multilayer Ceramic Capacitor, 0.1 µF, 50 V, 0402 [1005 Metric], ± 10%, X5R, GRM Series"
			(at 383.54 80.01 0)
			(effects
				(font
					(size 1.27 1.27)
				)
				(hide yes)
			)
		)
		(property "MPN" "GRM155R61H104KE14D"
			(at 365.76 100.33 0)
			(effects
				(font
					(size 1.27 1.27)
					(thickness 0.15)
				)
				(justify left bottom)
				(hide yes)
			)
		)
		(property "Manufacturer" "Murata"
			(at 363.22 100.33 0)
			(effects
				(font
					(size 1.27 1.27)
					(thickness 0.15)
				)
				(justify left bottom)
				(hide yes)
			)
		)
		(property "License" "Apache-2.0"
			(at 360.68 100.33 0)
			(effects
				(font
					(size 1.27 1.27)
					(thickness 0.15)
				)
				(justify left bottom)
				(hide yes)
			)
		)
		(property "Author" "Antmicro"
			(at 358.14 100.33 0)
			(effects
				(font
					(size 1.27 1.27)
					(thickness 0.15)
				)
				(justify left bottom)
				(hide yes)
			)
		)
		(property "Val" "100n"
			(at 384.81 85.09 90)
			(effects
				(font
					(size 1.27 1.27)
					(thickness 0.15)
				)
				(justify left bottom)
			)
		)
		(property "Voltage" "50V"
			(at 355.6 100.33 0)
			(effects
				(font
					(size 1.27 1.27)
				)
				(justify left bottom)
				(hide yes)
			)
		)
		(property "Dielectric" "X5R"
			(at 353.06 100.33 0)
			(effects
				(font
					(size 1.27 1.27)
				)
				(justify left bottom)
				(hide yes)
			)
		)
		(property "Public" ""
			(at 350.52 100.33 0)
			(effects
				(font
					(size 1.27 1.27)
				)
				(justify left bottom)
				(hide yes)
			)
		)
		(pin "2"
		)
		(pin "1"
		)
		(instances
			(project "polarfire-som"
				(path ""
					(reference "C19")
					(unit 1)
				)
			)
		)
	)
	(symbol
		(lib_id "antmicropower:PWR_FLAG")
		(at 331.47 102.87 90)
		(mirror x)
		(unit 1)
		(exclude_from_sim no)
		(in_bom yes)
		(on_board yes)
		(dnp no)
		(property "Reference" "#FLG01"
			(at 329.565 102.87 0)
			(effects
				(font
					(size 1.27 1.27)
				)
				(hide yes)
			)
		)
		(property "Value" "PWR_FLAG"
			(at 325.12 100.33 90)
			(effects
				(font
					(size 1.27 1.27)
				)
			)
		)
		(property "Footprint" ""
			(at 331.47 102.87 0)
			(effects
				(font
					(size 1.27 1.27)
				)
				(hide yes)
			)
		)
		(property "Datasheet" ""
			(at 331.47 102.87 0)
			(effects
				(font
					(size 1.27 1.27)
				)
				(hide yes)
			)
		)
		(property "Description" ""
			(at 331.47 102.87 0)
			(effects
				(font
					(size 1.27 1.27)
				)
				(hide yes)
			)
		)
		(pin "1"
		)
		(instances
			(project "polarfire-som"
				(path ""
					(reference "#FLG01")
					(unit 1)
				)
			)
		)
	)
	(symbol
		(lib_id "antmicroCapacitors0402:C_100n_0402")
		(at 193.04 226.06 270)
		(unit 1)
		(exclude_from_sim no)
		(in_bom yes)
		(on_board yes)
		(dnp no)
		(property "Reference" "C123"
			(at 196.85 226.06 90)
			(effects
				(font
					(size 1.27 1.27)
					(thickness 0.15)
				)
			)
		)
		(property "Value" "C_100n_0402"
			(at 182.88 246.38 0)
			(effects
				(font
					(size 1.27 1.27)
					(thickness 0.15)
				)
				(justify left bottom)
				(hide yes)
			)
		)
		(property "Footprint" "antmicro-footprints:C_0402_1005Metric"
			(at 180.34 246.38 0)
			(effects
				(font
					(size 1.27 1.27)
					(thickness 0.15)
				)
				(justify left bottom)
				(hide yes)
			)
		)
		(property "Datasheet" "https://www.murata.com/products/productdetail?partno=GRM155R61H104KE14%23"
			(at 177.8 246.38 0)
			(effects
				(font
					(size 1.27 1.27)
					(thickness 0.15)
				)
				(justify left bottom)
				(hide yes)
			)
		)
		(property "Description" "SMD Multilayer Ceramic Capacitor, 0.1 µF, 50 V, 0402 [1005 Metric], ± 10%, X5R, GRM Series"
			(at 193.04 226.06 0)
			(effects
				(font
					(size 1.27 1.27)
				)
				(hide yes)
			)
		)
		(property "MPN" "GRM155R61H104KE14D"
			(at 175.26 246.38 0)
			(effects
				(font
					(size 1.27 1.27)
					(thickness 0.15)
				)
				(justify left bottom)
				(hide yes)
			)
		)
		(property "Manufacturer" "Murata"
			(at 172.72 246.38 0)
			(effects
				(font
					(size 1.27 1.27)
					(thickness 0.15)
				)
				(justify left bottom)
				(hide yes)
			)
		)
		(property "License" "Apache-2.0"
			(at 170.18 246.38 0)
			(effects
				(font
					(size 1.27 1.27)
					(thickness 0.15)
				)
				(justify left bottom)
				(hide yes)
			)
		)
		(property "Author" "Antmicro"
			(at 167.64 246.38 0)
			(effects
				(font
					(size 1.27 1.27)
					(thickness 0.15)
				)
				(justify left bottom)
				(hide yes)
			)
		)
		(property "Val" "100n"
			(at 194.31 231.14 90)
			(effects
				(font
					(size 1.27 1.27)
					(thickness 0.15)
				)
				(justify left bottom)
			)
		)
		(property "Voltage" "50V"
			(at 165.1 246.38 0)
			(effects
				(font
					(size 1.27 1.27)
				)
				(justify left bottom)
				(hide yes)
			)
		)
		(property "Dielectric" "X5R"
			(at 162.56 246.38 0)
			(effects
				(font
					(size 1.27 1.27)
				)
				(justify left bottom)
				(hide yes)
			)
		)
		(property "Public" ""
			(at 160.02 246.38 0)
			(effects
				(font
					(size 1.27 1.27)
				)
				(justify left bottom)
				(hide yes)
			)
		)
		(pin "2"
		)
		(pin "1"
		)
		(instances
			(project "polarfire-som"
				(path ""
					(reference "C123")
					(unit 1)
				)
			)
		)
	)
	(symbol
		(lib_id "antmicroLogicTranslatorsLevelShifters:NTS0102_XSON")
		(at 311.15 78.74 0)
		(unit 1)
		(exclude_from_sim no)
		(in_bom yes)
		(on_board yes)
		(dnp no)
		(property "Reference" "U19"
			(at 321.31 71.12 0)
			(effects
				(font
					(size 1.27 1.27)
					(thickness 0.15)
				)
			)
		)
		(property "Value" "NTS0102_XSON"
			(at 346.71 86.36 0)
			(effects
				(font
					(size 1.27 1.27)
					(thickness 0.15)
				)
				(justify left bottom)
				(hide yes)
			)
		)
		(property "Footprint" "antmicro-footprints:XSON-8_1x1.95mm_P0.5mm"
			(at 346.71 88.9 0)
			(effects
				(font
					(size 1.27 1.27)
					(thickness 0.15)
				)
				(justify left bottom)
				(hide yes)
			)
		)
		(property "Datasheet" "http://www.farnell.com/datasheets/1760723.pdf"
			(at 346.71 91.44 0)
			(effects
				(font
					(size 1.27 1.27)
					(thickness 0.15)
				)
				(justify left bottom)
				(hide yes)
			)
		)
		(property "Description" "Transceiver, 1.65 V to 3.6 V, XSON-8"
			(at 311.15 78.74 0)
			(effects
				(font
					(size 1.27 1.27)
				)
				(hide yes)
			)
		)
		(property "MPN" "NTS0102GT"
			(at 321.31 73.66 0)
			(effects
				(font
					(size 1.27 1.27)
					(thickness 0.15)
				)
			)
		)
		(property "Manufacturer" "NXP"
			(at 346.71 93.98 0)
			(effects
				(font
					(size 1.27 1.27)
					(thickness 0.15)
				)
				(justify left bottom)
				(hide yes)
			)
		)
		(property "Author" "Antmicro"
			(at 346.71 96.52 0)
			(effects
				(font
					(size 1.27 1.27)
					(thickness 0.15)
				)
				(justify left bottom)
				(hide yes)
			)
		)
		(property "License" "Apache-2.0"
			(at 346.71 99.06 0)
			(effects
				(font
					(size 1.27 1.27)
					(thickness 0.15)
				)
				(justify left bottom)
				(hide yes)
			)
		)
		(pin "8"
		)
		(pin "7"
		)
		(pin "3"
		)
		(pin "2"
		)
		(pin "1"
		)
		(pin "6"
		)
		(pin "5"
		)
		(pin "4"
		)
		(instances
			(project "polarfire-som"
				(path ""
					(reference "U19")
					(unit 1)
				)
			)
		)
	)
	(symbol
		(lib_id "antmicropower:+3V3")
		(at 365.76 165.1 0)
		(mirror y)
		(unit 1)
		(exclude_from_sim no)
		(in_bom yes)
		(on_board yes)
		(dnp no)
		(property "Reference" "#PWR0153"
			(at 350.52 165.1 0)
			(effects
				(font
					(size 1.27 1.27)
					(thickness 0.15)
				)
				(justify left bottom)
				(hide yes)
			)
		)
		(property "Value" "+3V3"
			(at 365.125 160.02 0)
			(effects
				(font
					(size 1.27 1.27)
					(thickness 0.15)
				)
			)
		)
		(property "Footprint" ""
			(at 350.52 172.72 0)
			(effects
				(font
					(size 1.27 1.27)
					(thickness 0.15)
				)
				(justify left bottom)
				(hide yes)
			)
		)
		(property "Datasheet" ""
			(at 350.52 175.26 0)
			(effects
				(font
					(size 1.27 1.27)
					(thickness 0.15)
				)
				(justify left bottom)
				(hide yes)
			)
		)
		(property "Description" ""
			(at 365.76 165.1 0)
			(effects
				(font
					(size 1.27 1.27)
				)
				(hide yes)
			)
		)
		(property "Author" "Antmicro"
			(at 350.52 167.64 0)
			(effects
				(font
					(size 1.27 1.27)
					(thickness 0.15)
				)
				(justify left bottom)
				(hide yes)
			)
		)
		(property "License" "Apache-2.0"
			(at 350.52 170.18 0)
			(effects
				(font
					(size 1.27 1.27)
					(thickness 0.15)
				)
				(justify left bottom)
				(hide yes)
			)
		)
		(pin "1"
		)
		(instances
			(project "polarfire-som"
				(path ""
					(reference "#PWR0153")
					(unit 1)
				)
			)
		)
	)
	(symbol
		(lib_id "antmicropower:VDDI")
		(at 307.34 39.37 0)
		(mirror y)
		(unit 1)
		(exclude_from_sim no)
		(in_bom yes)
		(on_board yes)
		(dnp no)
		(fields_autoplaced yes)
		(property "Reference" "#PWR0210"
			(at 307.34 43.18 0)
			(effects
				(font
					(size 1.27 1.27)
				)
				(hide yes)
			)
		)
		(property "Value" "VDD"
			(at 307.34 34.925 0)
			(effects
				(font
					(size 1.27 1.27)
				)
			)
		)
		(property "Footprint" ""
			(at 307.34 39.37 0)
			(effects
				(font
					(size 1.27 1.27)
				)
				(hide yes)
			)
		)
		(property "Datasheet" ""
			(at 307.34 39.37 0)
			(effects
				(font
					(size 1.27 1.27)
				)
				(hide yes)
			)
		)
		(property "Description" ""
			(at 307.34 39.37 0)
			(effects
				(font
					(size 1.27 1.27)
				)
				(hide yes)
			)
		)
		(pin "1"
		)
		(instances
			(project "polarfire-som"
				(path ""
					(reference "#PWR0210")
					(unit 1)
				)
			)
		)
	)
	(symbol
		(lib_id "antmicropower:GND")
		(at 156.21 213.36 0)
		(mirror y)
		(unit 1)
		(exclude_from_sim no)
		(in_bom yes)
		(on_board yes)
		(dnp no)
		(fields_autoplaced yes)
		(property "Reference" "#PWR0310"
			(at 147.32 215.9 0)
			(effects
				(font
					(size 1.27 1.27)
					(thickness 0.15)
				)
				(justify left bottom)
				(hide yes)
			)
		)
		(property "Value" "GND"
			(at 156.21 218.44 0)
			(effects
				(font
					(size 1.27 1.27)
					(thickness 0.15)
				)
			)
		)
		(property "Footprint" ""
			(at 147.32 220.98 0)
			(effects
				(font
					(size 1.27 1.27)
					(thickness 0.15)
				)
				(justify left bottom)
				(hide yes)
			)
		)
		(property "Datasheet" ""
			(at 147.32 226.06 0)
			(effects
				(font
					(size 1.27 1.27)
					(thickness 0.15)
				)
				(justify left bottom)
				(hide yes)
			)
		)
		(property "Description" ""
			(at 156.21 213.36 0)
			(effects
				(font
					(size 1.27 1.27)
				)
				(hide yes)
			)
		)
		(property "Author" "Antmicro"
			(at 147.32 220.98 0)
			(effects
				(font
					(size 1.27 1.27)
					(thickness 0.15)
				)
				(justify left bottom)
				(hide yes)
			)
		)
		(property "License" "Apache-2.0"
			(at 147.32 223.52 0)
			(effects
				(font
					(size 1.27 1.27)
					(thickness 0.15)
				)
				(justify left bottom)
				(hide yes)
			)
		)
		(pin "1"
		)
		(instances
			(project "polarfire-som"
				(path ""
					(reference "#PWR0310")
					(unit 1)
				)
			)
		)
	)
	(symbol
		(lib_id "antmicroCapacitors0402:C_100n_0402")
		(at 367.03 223.52 270)
		(unit 1)
		(exclude_from_sim no)
		(in_bom yes)
		(on_board yes)
		(dnp no)
		(property "Reference" "C36"
			(at 370.84 223.52 90)
			(effects
				(font
					(size 1.27 1.27)
					(thickness 0.15)
				)
			)
		)
		(property "Value" "C_100n_0402"
			(at 356.87 243.84 0)
			(effects
				(font
					(size 1.27 1.27)
					(thickness 0.15)
				)
				(justify left bottom)
				(hide yes)
			)
		)
		(property "Footprint" "antmicro-footprints:C_0402_1005Metric"
			(at 354.33 243.84 0)
			(effects
				(font
					(size 1.27 1.27)
					(thickness 0.15)
				)
				(justify left bottom)
				(hide yes)
			)
		)
		(property "Datasheet" "https://www.murata.com/products/productdetail?partno=GRM155R61H104KE14%23"
			(at 351.79 243.84 0)
			(effects
				(font
					(size 1.27 1.27)
					(thickness 0.15)
				)
				(justify left bottom)
				(hide yes)
			)
		)
		(property "Description" "SMD Multilayer Ceramic Capacitor, 0.1 µF, 50 V, 0402 [1005 Metric], ± 10%, X5R, GRM Series"
			(at 367.03 223.52 0)
			(effects
				(font
					(size 1.27 1.27)
				)
				(hide yes)
			)
		)
		(property "MPN" "GRM155R61H104KE14D"
			(at 349.25 243.84 0)
			(effects
				(font
					(size 1.27 1.27)
					(thickness 0.15)
				)
				(justify left bottom)
				(hide yes)
			)
		)
		(property "Manufacturer" "Murata"
			(at 346.71 243.84 0)
			(effects
				(font
					(size 1.27 1.27)
					(thickness 0.15)
				)
				(justify left bottom)
				(hide yes)
			)
		)
		(property "License" "Apache-2.0"
			(at 344.17 243.84 0)
			(effects
				(font
					(size 1.27 1.27)
					(thickness 0.15)
				)
				(justify left bottom)
				(hide yes)
			)
		)
		(property "Author" "Antmicro"
			(at 341.63 243.84 0)
			(effects
				(font
					(size 1.27 1.27)
					(thickness 0.15)
				)
				(justify left bottom)
				(hide yes)
			)
		)
		(property "Val" "100n"
			(at 368.3 228.6 90)
			(effects
				(font
					(size 1.27 1.27)
					(thickness 0.15)
				)
				(justify left bottom)
			)
		)
		(property "Voltage" "50V"
			(at 339.09 243.84 0)
			(effects
				(font
					(size 1.27 1.27)
				)
				(justify left bottom)
				(hide yes)
			)
		)
		(property "Dielectric" "X5R"
			(at 336.55 243.84 0)
			(effects
				(font
					(size 1.27 1.27)
				)
				(justify left bottom)
				(hide yes)
			)
		)
		(property "Public" ""
			(at 334.01 243.84 0)
			(effects
				(font
					(size 1.27 1.27)
				)
				(justify left bottom)
				(hide yes)
			)
		)
		(pin "2"
		)
		(pin "1"
		)
		(instances
			(project "polarfire-som"
				(path ""
					(reference "C36")
					(unit 1)
				)
			)
		)
	)
	(symbol
		(lib_id "antmicropower:GND")
		(at 93.98 256.54 0)
		(unit 1)
		(exclude_from_sim no)
		(in_bom yes)
		(on_board yes)
		(dnp no)
		(property "Reference" "#PWR0289"
			(at 102.87 259.08 0)
			(effects
				(font
					(size 1.27 1.27)
					(thickness 0.15)
				)
				(justify left bottom)
				(hide yes)
			)
		)
		(property "Value" "GND"
			(at 93.98 260.35 0)
			(effects
				(font
					(size 1.27 1.27)
					(thickness 0.15)
				)
			)
		)
		(property "Footprint" ""
			(at 102.87 264.16 0)
			(effects
				(font
					(size 1.27 1.27)
					(thickness 0.15)
				)
				(justify left bottom)
				(hide yes)
			)
		)
		(property "Datasheet" ""
			(at 102.87 269.24 0)
			(effects
				(font
					(size 1.27 1.27)
					(thickness 0.15)
				)
				(justify left bottom)
				(hide yes)
			)
		)
		(property "Description" ""
			(at 93.98 256.54 0)
			(effects
				(font
					(size 1.27 1.27)
				)
				(hide yes)
			)
		)
		(property "Author" "Antmicro"
			(at 102.87 264.16 0)
			(effects
				(font
					(size 1.27 1.27)
					(thickness 0.15)
				)
				(justify left bottom)
				(hide yes)
			)
		)
		(property "License" "Apache-2.0"
			(at 102.87 266.7 0)
			(effects
				(font
					(size 1.27 1.27)
					(thickness 0.15)
				)
				(justify left bottom)
				(hide yes)
			)
		)
		(pin "1"
		)
		(instances
			(project "polarfire-som"
				(path ""
					(reference "#PWR0289")
					(unit 1)
				)
			)
		)
	)
	(symbol
		(lib_id "antmicropower:GND")
		(at 335.28 48.26 0)
		(unit 1)
		(exclude_from_sim no)
		(in_bom yes)
		(on_board yes)
		(dnp no)
		(property "Reference" "#PWR0353"
			(at 344.17 50.8 0)
			(effects
				(font
					(size 1.27 1.27)
					(thickness 0.15)
				)
				(justify left bottom)
				(hide yes)
			)
		)
		(property "Value" "GND"
			(at 339.09 49.53 0)
			(effects
				(font
					(size 1.27 1.27)
					(thickness 0.15)
				)
			)
		)
		(property "Footprint" ""
			(at 344.17 55.88 0)
			(effects
				(font
					(size 1.27 1.27)
					(thickness 0.15)
				)
				(justify left bottom)
				(hide yes)
			)
		)
		(property "Datasheet" ""
			(at 344.17 60.96 0)
			(effects
				(font
					(size 1.27 1.27)
					(thickness 0.15)
				)
				(justify left bottom)
				(hide yes)
			)
		)
		(property "Description" ""
			(at 335.28 48.26 0)
			(effects
				(font
					(size 1.27 1.27)
				)
				(hide yes)
			)
		)
		(property "Author" "Antmicro"
			(at 344.17 55.88 0)
			(effects
				(font
					(size 1.27 1.27)
					(thickness 0.15)
				)
				(justify left bottom)
				(hide yes)
			)
		)
		(property "License" "Apache-2.0"
			(at 344.17 58.42 0)
			(effects
				(font
					(size 1.27 1.27)
					(thickness 0.15)
				)
				(justify left bottom)
				(hide yes)
			)
		)
		(pin "1"
		)
		(instances
			(project "polarfire-som"
				(path ""
					(reference "#PWR0353")
					(unit 1)
				)
			)
		)
	)
	(symbol
		(lib_id "antmicroCapacitors0402:C_100n_0402")
		(at 304.8 102.87 90)
		(mirror x)
		(unit 1)
		(exclude_from_sim no)
		(in_bom yes)
		(on_board yes)
		(dnp no)
		(property "Reference" "C130"
			(at 300.99 102.87 90)
			(effects
				(font
					(size 1.27 1.27)
					(thickness 0.15)
				)
			)
		)
		(property "Value" "C_100n_0402"
			(at 314.96 123.19 0)
			(effects
				(font
					(size 1.27 1.27)
					(thickness 0.15)
				)
				(justify left bottom)
				(hide yes)
			)
		)
		(property "Footprint" "antmicro-footprints:C_0402_1005Metric"
			(at 317.5 123.19 0)
			(effects
				(font
					(size 1.27 1.27)
					(thickness 0.15)
				)
				(justify left bottom)
				(hide yes)
			)
		)
		(property "Datasheet" "https://www.murata.com/products/productdetail?partno=GRM155R61H104KE14%23"
			(at 320.04 123.19 0)
			(effects
				(font
					(size 1.27 1.27)
					(thickness 0.15)
				)
				(justify left bottom)
				(hide yes)
			)
		)
		(property "Description" "SMD Multilayer Ceramic Capacitor, 0.1 µF, 50 V, 0402 [1005 Metric], ± 10%, X5R, GRM Series"
			(at 304.8 102.87 0)
			(effects
				(font
					(size 1.27 1.27)
				)
				(hide yes)
			)
		)
		(property "MPN" "GRM155R61H104KE14D"
			(at 322.58 123.19 0)
			(effects
				(font
					(size 1.27 1.27)
					(thickness 0.15)
				)
				(justify left bottom)
				(hide yes)
			)
		)
		(property "Manufacturer" "Murata"
			(at 325.12 123.19 0)
			(effects
				(font
					(size 1.27 1.27)
					(thickness 0.15)
				)
				(justify left bottom)
				(hide yes)
			)
		)
		(property "License" "Apache-2.0"
			(at 327.66 123.19 0)
			(effects
				(font
					(size 1.27 1.27)
					(thickness 0.15)
				)
				(justify left bottom)
				(hide yes)
			)
		)
		(property "Author" "Antmicro"
			(at 330.2 123.19 0)
			(effects
				(font
					(size 1.27 1.27)
					(thickness 0.15)
				)
				(justify left bottom)
				(hide yes)
			)
		)
		(property "Val" "100n"
			(at 303.53 107.95 90)
			(effects
				(font
					(size 1.27 1.27)
					(thickness 0.15)
				)
				(justify left bottom)
			)
		)
		(property "Voltage" "50V"
			(at 332.74 123.19 0)
			(effects
				(font
					(size 1.27 1.27)
				)
				(justify left bottom)
				(hide yes)
			)
		)
		(property "Dielectric" "X5R"
			(at 335.28 123.19 0)
			(effects
				(font
					(size 1.27 1.27)
				)
				(justify left bottom)
				(hide yes)
			)
		)
		(property "Public" ""
			(at 337.82 123.19 0)
			(effects
				(font
					(size 1.27 1.27)
				)
				(justify left bottom)
				(hide yes)
			)
		)
		(pin "2"
		)
		(pin "1"
		)
		(instances
			(project "polarfire-som"
				(path ""
					(reference "C130")
					(unit 1)
				)
			)
		)
	)
	(symbol
		(lib_id "antmicroResistors0402:R_470R_0402")
		(at 36.83 232.41 90)
		(unit 1)
		(exclude_from_sim no)
		(in_bom yes)
		(on_board yes)
		(dnp no)
		(fields_autoplaced yes)
		(property "Reference" "R72"
			(at 39.37 228.6 90)
			(effects
				(font
					(size 1.27 1.27)
					(thickness 0.15)
				)
				(justify right)
			)
		)
		(property "Value" "R_470R_0402"
			(at 49.53 212.09 0)
			(effects
				(font
					(size 1.27 1.27)
					(thickness 0.15)
				)
				(justify left bottom)
				(hide yes)
			)
		)
		(property "Footprint" "antmicro-footprints:R_0402_1005Metric"
			(at 52.07 212.09 0)
			(effects
				(font
					(size 1.27 1.27)
					(thickness 0.15)
				)
				(justify left bottom)
				(hide yes)
			)
		)
		(property "Datasheet" "https://www.bourns.com/docs/product-datasheets/cr.pdf"
			(at 54.61 212.09 0)
			(effects
				(font
					(size 1.27 1.27)
					(thickness 0.15)
				)
				(justify left bottom)
				(hide yes)
			)
		)
		(property "Description" "SMD Chip Resistor, 470 ohm, ± 1%, 62.5 mW, 0402 [1005 Metric], Thick Film, General Purpose"
			(at 36.83 232.41 0)
			(effects
				(font
					(size 1.27 1.27)
				)
				(hide yes)
			)
		)
		(property "MPN" "CR0402-FX-4700GLF"
			(at 57.15 212.09 0)
			(effects
				(font
					(size 1.27 1.27)
					(thickness 0.15)
				)
				(justify left bottom)
				(hide yes)
			)
		)
		(property "Manufacturer" "Bourns"
			(at 59.69 212.09 0)
			(effects
				(font
					(size 1.27 1.27)
					(thickness 0.15)
				)
				(justify left bottom)
				(hide yes)
			)
		)
		(property "License" "Apache-2.0"
			(at 62.23 212.09 0)
			(effects
				(font
					(size 1.27 1.27)
					(thickness 0.15)
				)
				(justify left bottom)
				(hide yes)
			)
		)
		(property "Author" "Antmicro"
			(at 64.77 212.09 0)
			(effects
				(font
					(size 1.27 1.27)
					(thickness 0.15)
				)
				(justify left bottom)
				(hide yes)
			)
		)
		(property "Val" "470R"
			(at 39.37 231.14 90)
			(effects
				(font
					(size 1.27 1.27)
					(thickness 0.15)
				)
				(justify right)
			)
		)
		(property "Tolerance" "1%"
			(at 46.99 212.09 0)
			(effects
				(font
					(size 1.27 1.27)
				)
				(justify left bottom)
				(hide yes)
			)
		)
		(property "Public" ""
			(at 67.31 212.09 0)
			(effects
				(font
					(size 1.27 1.27)
				)
				(justify left bottom)
				(hide yes)
			)
		)
		(pin "2"
		)
		(pin "1"
		)
		(instances
			(project "polarfire-som"
				(path ""
					(reference "R72")
					(unit 1)
				)
			)
		)
	)
	(symbol
		(lib_id "antmicroLogicTranslatorsLevelShifters:NTS0102_XSON")
		(at 134.62 204.47 0)
		(unit 1)
		(exclude_from_sim no)
		(in_bom yes)
		(on_board yes)
		(dnp no)
		(fields_autoplaced yes)
		(property "Reference" "U25"
			(at 144.78 196.85 0)
			(effects
				(font
					(size 1.27 1.27)
					(thickness 0.15)
				)
			)
		)
		(property "Value" "NTS0102_XSON"
			(at 170.18 212.09 0)
			(effects
				(font
					(size 1.27 1.27)
					(thickness 0.15)
				)
				(justify left bottom)
				(hide yes)
			)
		)
		(property "Footprint" "antmicro-footprints:XSON-8_1x1.95mm_P0.5mm"
			(at 170.18 214.63 0)
			(effects
				(font
					(size 1.27 1.27)
					(thickness 0.15)
				)
				(justify left bottom)
				(hide yes)
			)
		)
		(property "Datasheet" "http://www.farnell.com/datasheets/1760723.pdf"
			(at 170.18 217.17 0)
			(effects
				(font
					(size 1.27 1.27)
					(thickness 0.15)
				)
				(justify left bottom)
				(hide yes)
			)
		)
		(property "Description" "Transceiver, 1.65 V to 3.6 V, XSON-8"
			(at 134.62 204.47 0)
			(effects
				(font
					(size 1.27 1.27)
				)
				(hide yes)
			)
		)
		(property "MPN" "NTS0102GT"
			(at 144.78 199.39 0)
			(effects
				(font
					(size 1.27 1.27)
					(thickness 0.15)
				)
			)
		)
		(property "Manufacturer" "NXP"
			(at 170.18 219.71 0)
			(effects
				(font
					(size 1.27 1.27)
					(thickness 0.15)
				)
				(justify left bottom)
				(hide yes)
			)
		)
		(property "Author" "Antmicro"
			(at 170.18 222.25 0)
			(effects
				(font
					(size 1.27 1.27)
					(thickness 0.15)
				)
				(justify left bottom)
				(hide yes)
			)
		)
		(property "License" "Apache-2.0"
			(at 170.18 224.79 0)
			(effects
				(font
					(size 1.27 1.27)
					(thickness 0.15)
				)
				(justify left bottom)
				(hide yes)
			)
		)
		(pin "2"
		)
		(pin "6"
		)
		(pin "7"
		)
		(pin "5"
		)
		(pin "4"
		)
		(pin "3"
		)
		(pin "1"
		)
		(pin "8"
		)
		(instances
			(project "polarfire-som"
				(path ""
					(reference "U25")
					(unit 1)
				)
			)
		)
	)
	(symbol
		(lib_id "antmicropower:GND")
		(at 383.54 86.36 0)
		(mirror y)
		(unit 1)
		(exclude_from_sim no)
		(in_bom yes)
		(on_board yes)
		(dnp no)
		(property "Reference" "#PWR0301"
			(at 374.65 88.9 0)
			(effects
				(font
					(size 1.27 1.27)
					(thickness 0.15)
				)
				(justify left bottom)
				(hide yes)
			)
		)
		(property "Value" "GND"
			(at 383.54 90.17 0)
			(effects
				(font
					(size 1.27 1.27)
					(thickness 0.15)
				)
			)
		)
		(property "Footprint" ""
			(at 374.65 93.98 0)
			(effects
				(font
					(size 1.27 1.27)
					(thickness 0.15)
				)
				(justify left bottom)
				(hide yes)
			)
		)
		(property "Datasheet" ""
			(at 374.65 99.06 0)
			(effects
				(font
					(size 1.27 1.27)
					(thickness 0.15)
				)
				(justify left bottom)
				(hide yes)
			)
		)
		(property "Description" ""
			(at 383.54 86.36 0)
			(effects
				(font
					(size 1.27 1.27)
				)
				(hide yes)
			)
		)
		(property "Author" "Antmicro"
			(at 374.65 93.98 0)
			(effects
				(font
					(size 1.27 1.27)
					(thickness 0.15)
				)
				(justify left bottom)
				(hide yes)
			)
		)
		(property "License" "Apache-2.0"
			(at 374.65 96.52 0)
			(effects
				(font
					(size 1.27 1.27)
					(thickness 0.15)
				)
				(justify left bottom)
				(hide yes)
			)
		)
		(pin "1"
		)
		(instances
			(project "polarfire-som"
				(path ""
					(reference "#PWR0301")
					(unit 1)
				)
			)
		)
	)
	(symbol
		(lib_id "antmicroResistors0402:R_100k_0402")
		(at 29.21 252.73 270)
		(mirror x)
		(unit 1)
		(exclude_from_sim no)
		(in_bom yes)
		(on_board yes)
		(dnp no)
		(property "Reference" "R80"
			(at 27.94 248.92 90)
			(effects
				(font
					(size 1.27 1.27)
					(thickness 0.15)
				)
				(justify right)
			)
		)
		(property "Value" "R_100k_0402"
			(at 16.51 232.41 0)
			(effects
				(font
					(size 1.27 1.27)
					(thickness 0.15)
				)
				(justify left bottom)
				(hide yes)
			)
		)
		(property "Footprint" "antmicro-footprints:R_0402_1005Metric"
			(at 13.97 232.41 0)
			(effects
				(font
					(size 1.27 1.27)
					(thickness 0.15)
				)
				(justify left bottom)
				(hide yes)
			)
		)
		(property "Datasheet" "https://www.bourns.com/docs/product-datasheets/cr.pdf"
			(at 11.43 232.41 0)
			(effects
				(font
					(size 1.27 1.27)
					(thickness 0.15)
				)
				(justify left bottom)
				(hide yes)
			)
		)
		(property "Description" "SMD Chip Resistor, 100 kohm, ± 1%, 62.5 mW, 0402 [1005 Metric], Thick Film, General Purpose"
			(at 29.21 252.73 0)
			(effects
				(font
					(size 1.27 1.27)
				)
				(hide yes)
			)
		)
		(property "MPN" "CR0402-FX-1003GLF"
			(at 8.89 232.41 0)
			(effects
				(font
					(size 1.27 1.27)
					(thickness 0.15)
				)
				(justify left bottom)
				(hide yes)
			)
		)
		(property "Manufacturer" "Bourns"
			(at 6.35 232.41 0)
			(effects
				(font
					(size 1.27 1.27)
					(thickness 0.15)
				)
				(justify left bottom)
				(hide yes)
			)
		)
		(property "License" "Apache-2.0"
			(at 3.81 232.41 0)
			(effects
				(font
					(size 1.27 1.27)
					(thickness 0.15)
				)
				(justify left bottom)
				(hide yes)
			)
		)
		(property "Author" "Antmicro"
			(at 1.27 232.41 0)
			(effects
				(font
					(size 1.27 1.27)
					(thickness 0.15)
				)
				(justify left bottom)
				(hide yes)
			)
		)
		(property "Val" "100k"
			(at 27.94 251.46 90)
			(effects
				(font
					(size 1.27 1.27)
					(thickness 0.15)
				)
				(justify right)
			)
		)
		(property "Tolerance" "1%"
			(at 19.05 232.41 0)
			(effects
				(font
					(size 1.27 1.27)
				)
				(justify left bottom)
				(hide yes)
			)
		)
		(property "Public" ""
			(at -1.27 232.41 0)
			(effects
				(font
					(size 1.27 1.27)
				)
				(justify left bottom)
				(hide yes)
			)
		)
		(pin "1"
		)
		(pin "2"
		)
		(instances
			(project "polarfire-som"
				(path ""
					(reference "R80")
					(unit 1)
				)
			)
		)
	)
	(symbol
		(lib_id "antmicropower:+3V3")
		(at 156.21 257.81 0)
		(mirror y)
		(unit 1)
		(exclude_from_sim no)
		(in_bom yes)
		(on_board yes)
		(dnp no)
		(fields_autoplaced yes)
		(property "Reference" "#PWR0318"
			(at 140.97 257.81 0)
			(effects
				(font
					(size 1.27 1.27)
					(thickness 0.15)
				)
				(justify left bottom)
				(hide yes)
			)
		)
		(property "Value" "+3V3"
			(at 156.21 252.73 0)
			(effects
				(font
					(size 1.27 1.27)
					(thickness 0.15)
				)
			)
		)
		(property "Footprint" ""
			(at 140.97 265.43 0)
			(effects
				(font
					(size 1.27 1.27)
					(thickness 0.15)
				)
				(justify left bottom)
				(hide yes)
			)
		)
		(property "Datasheet" ""
			(at 140.97 267.97 0)
			(effects
				(font
					(size 1.27 1.27)
					(thickness 0.15)
				)
				(justify left bottom)
				(hide yes)
			)
		)
		(property "Description" ""
			(at 156.21 257.81 0)
			(effects
				(font
					(size 1.27 1.27)
				)
				(hide yes)
			)
		)
		(property "Author" "Antmicro"
			(at 140.97 260.35 0)
			(effects
				(font
					(size 1.27 1.27)
					(thickness 0.15)
				)
				(justify left bottom)
				(hide yes)
			)
		)
		(property "License" "Apache-2.0"
			(at 140.97 262.89 0)
			(effects
				(font
					(size 1.27 1.27)
					(thickness 0.15)
				)
				(justify left bottom)
				(hide yes)
			)
		)
		(pin "1"
		)
		(instances
			(project "polarfire-som"
				(path ""
					(reference "#PWR0318")
					(unit 1)
				)
			)
		)
	)
	(symbol
		(lib_id "antmicropower:GND")
		(at 334.01 88.9 0)
		(mirror y)
		(unit 1)
		(exclude_from_sim no)
		(in_bom yes)
		(on_board yes)
		(dnp no)
		(property "Reference" "#PWR0352"
			(at 325.12 91.44 0)
			(effects
				(font
					(size 1.27 1.27)
					(thickness 0.15)
				)
				(justify left bottom)
				(hide yes)
			)
		)
		(property "Value" "GND"
			(at 334.01 92.71 0)
			(effects
				(font
					(size 1.27 1.27)
					(thickness 0.15)
				)
			)
		)
		(property "Footprint" ""
			(at 325.12 96.52 0)
			(effects
				(font
					(size 1.27 1.27)
					(thickness 0.15)
				)
				(justify left bottom)
				(hide yes)
			)
		)
		(property "Datasheet" ""
			(at 325.12 101.6 0)
			(effects
				(font
					(size 1.27 1.27)
					(thickness 0.15)
				)
				(justify left bottom)
				(hide yes)
			)
		)
		(property "Description" ""
			(at 334.01 88.9 0)
			(effects
				(font
					(size 1.27 1.27)
				)
				(hide yes)
			)
		)
		(property "Author" "Antmicro"
			(at 325.12 96.52 0)
			(effects
				(font
					(size 1.27 1.27)
					(thickness 0.15)
				)
				(justify left bottom)
				(hide yes)
			)
		)
		(property "License" "Apache-2.0"
			(at 325.12 99.06 0)
			(effects
				(font
					(size 1.27 1.27)
					(thickness 0.15)
				)
				(justify left bottom)
				(hide yes)
			)
		)
		(pin "1"
		)
		(instances
			(project "polarfire-som"
				(path ""
					(reference "#PWR0352")
					(unit 1)
				)
			)
		)
	)
	(symbol
		(lib_id "antmicropower:GND")
		(at 378.46 229.87 0)
		(mirror y)
		(unit 1)
		(exclude_from_sim no)
		(in_bom yes)
		(on_board yes)
		(dnp no)
		(property "Reference" "#PWR0351"
			(at 369.57 232.41 0)
			(effects
				(font
					(size 1.27 1.27)
					(thickness 0.15)
				)
				(justify left bottom)
				(hide yes)
			)
		)
		(property "Value" "GND"
			(at 378.46 233.68 0)
			(effects
				(font
					(size 1.27 1.27)
					(thickness 0.15)
				)
			)
		)
		(property "Footprint" ""
			(at 369.57 237.49 0)
			(effects
				(font
					(size 1.27 1.27)
					(thickness 0.15)
				)
				(justify left bottom)
				(hide yes)
			)
		)
		(property "Datasheet" ""
			(at 369.57 242.57 0)
			(effects
				(font
					(size 1.27 1.27)
					(thickness 0.15)
				)
				(justify left bottom)
				(hide yes)
			)
		)
		(property "Description" ""
			(at 378.46 229.87 0)
			(effects
				(font
					(size 1.27 1.27)
				)
				(hide yes)
			)
		)
		(property "Author" "Antmicro"
			(at 369.57 237.49 0)
			(effects
				(font
					(size 1.27 1.27)
					(thickness 0.15)
				)
				(justify left bottom)
				(hide yes)
			)
		)
		(property "License" "Apache-2.0"
			(at 369.57 240.03 0)
			(effects
				(font
					(size 1.27 1.27)
					(thickness 0.15)
				)
				(justify left bottom)
				(hide yes)
			)
		)
		(pin "1"
		)
		(instances
			(project "polarfire-som"
				(path ""
					(reference "#PWR0351")
					(unit 1)
				)
			)
		)
	)
	(symbol
		(lib_id "antmicroCapacitors0402:C_100n_0402")
		(at 378.46 223.52 270)
		(unit 1)
		(exclude_from_sim no)
		(in_bom yes)
		(on_board yes)
		(dnp no)
		(property "Reference" "C45"
			(at 382.27 223.52 90)
			(effects
				(font
					(size 1.27 1.27)
					(thickness 0.15)
				)
			)
		)
		(property "Value" "C_100n_0402"
			(at 368.3 243.84 0)
			(effects
				(font
					(size 1.27 1.27)
					(thickness 0.15)
				)
				(justify left bottom)
				(hide yes)
			)
		)
		(property "Footprint" "antmicro-footprints:C_0402_1005Metric"
			(at 365.76 243.84 0)
			(effects
				(font
					(size 1.27 1.27)
					(thickness 0.15)
				)
				(justify left bottom)
				(hide yes)
			)
		)
		(property "Datasheet" "https://www.murata.com/products/productdetail?partno=GRM155R61H104KE14%23"
			(at 363.22 243.84 0)
			(effects
				(font
					(size 1.27 1.27)
					(thickness 0.15)
				)
				(justify left bottom)
				(hide yes)
			)
		)
		(property "Description" "SMD Multilayer Ceramic Capacitor, 0.1 µF, 50 V, 0402 [1005 Metric], ± 10%, X5R, GRM Series"
			(at 378.46 223.52 0)
			(effects
				(font
					(size 1.27 1.27)
				)
				(hide yes)
			)
		)
		(property "MPN" "GRM155R61H104KE14D"
			(at 360.68 243.84 0)
			(effects
				(font
					(size 1.27 1.27)
					(thickness 0.15)
				)
				(justify left bottom)
				(hide yes)
			)
		)
		(property "Manufacturer" "Murata"
			(at 358.14 243.84 0)
			(effects
				(font
					(size 1.27 1.27)
					(thickness 0.15)
				)
				(justify left bottom)
				(hide yes)
			)
		)
		(property "License" "Apache-2.0"
			(at 355.6 243.84 0)
			(effects
				(font
					(size 1.27 1.27)
					(thickness 0.15)
				)
				(justify left bottom)
				(hide yes)
			)
		)
		(property "Author" "Antmicro"
			(at 353.06 243.84 0)
			(effects
				(font
					(size 1.27 1.27)
					(thickness 0.15)
				)
				(justify left bottom)
				(hide yes)
			)
		)
		(property "Val" "100n"
			(at 379.73 228.6 90)
			(effects
				(font
					(size 1.27 1.27)
					(thickness 0.15)
				)
				(justify left bottom)
			)
		)
		(property "Voltage" "50V"
			(at 350.52 243.84 0)
			(effects
				(font
					(size 1.27 1.27)
				)
				(justify left bottom)
				(hide yes)
			)
		)
		(property "Dielectric" "X5R"
			(at 347.98 243.84 0)
			(effects
				(font
					(size 1.27 1.27)
				)
				(justify left bottom)
				(hide yes)
			)
		)
		(property "Public" ""
			(at 345.44 243.84 0)
			(effects
				(font
					(size 1.27 1.27)
				)
				(justify left bottom)
				(hide yes)
			)
		)
		(pin "2"
		)
		(pin "1"
		)
		(instances
			(project "polarfire-som"
				(path ""
					(reference "C45")
					(unit 1)
				)
			)
		)
	)
	(symbol
		(lib_id "antmicroCapacitors0402:C_100n_0402")
		(at 304.8 40.64 90)
		(mirror x)
		(unit 1)
		(exclude_from_sim no)
		(in_bom yes)
		(on_board yes)
		(dnp no)
		(property "Reference" "C132"
			(at 300.99 40.64 90)
			(effects
				(font
					(size 1.27 1.27)
					(thickness 0.15)
				)
			)
		)
		(property "Value" "C_100n_0402"
			(at 314.96 60.96 0)
			(effects
				(font
					(size 1.27 1.27)
					(thickness 0.15)
				)
				(justify left bottom)
				(hide yes)
			)
		)
		(property "Footprint" "antmicro-footprints:C_0402_1005Metric"
			(at 317.5 60.96 0)
			(effects
				(font
					(size 1.27 1.27)
					(thickness 0.15)
				)
				(justify left bottom)
				(hide yes)
			)
		)
		(property "Datasheet" "https://www.murata.com/products/productdetail?partno=GRM155R61H104KE14%23"
			(at 320.04 60.96 0)
			(effects
				(font
					(size 1.27 1.27)
					(thickness 0.15)
				)
				(justify left bottom)
				(hide yes)
			)
		)
		(property "Description" "SMD Multilayer Ceramic Capacitor, 0.1 µF, 50 V, 0402 [1005 Metric], ± 10%, X5R, GRM Series"
			(at 304.8 40.64 0)
			(effects
				(font
					(size 1.27 1.27)
				)
				(hide yes)
			)
		)
		(property "MPN" "GRM155R61H104KE14D"
			(at 322.58 60.96 0)
			(effects
				(font
					(size 1.27 1.27)
					(thickness 0.15)
				)
				(justify left bottom)
				(hide yes)
			)
		)
		(property "Manufacturer" "Murata"
			(at 325.12 60.96 0)
			(effects
				(font
					(size 1.27 1.27)
					(thickness 0.15)
				)
				(justify left bottom)
				(hide yes)
			)
		)
		(property "License" "Apache-2.0"
			(at 327.66 60.96 0)
			(effects
				(font
					(size 1.27 1.27)
					(thickness 0.15)
				)
				(justify left bottom)
				(hide yes)
			)
		)
		(property "Author" "Antmicro"
			(at 330.2 60.96 0)
			(effects
				(font
					(size 1.27 1.27)
					(thickness 0.15)
				)
				(justify left bottom)
				(hide yes)
			)
		)
		(property "Val" "100n"
			(at 303.53 45.72 90)
			(effects
				(font
					(size 1.27 1.27)
					(thickness 0.15)
				)
				(justify left bottom)
			)
		)
		(property "Voltage" "50V"
			(at 332.74 60.96 0)
			(effects
				(font
					(size 1.27 1.27)
				)
				(justify left bottom)
				(hide yes)
			)
		)
		(property "Dielectric" "X5R"
			(at 335.28 60.96 0)
			(effects
				(font
					(size 1.27 1.27)
				)
				(justify left bottom)
				(hide yes)
			)
		)
		(property "Public" ""
			(at 337.82 60.96 0)
			(effects
				(font
					(size 1.27 1.27)
				)
				(justify left bottom)
				(hide yes)
			)
		)
		(pin "2"
		)
		(pin "1"
		)
		(instances
			(project "polarfire-som"
				(path ""
					(reference "C132")
					(unit 1)
				)
			)
		)
	)
	(symbol
		(lib_id "antmicropower:GND")
		(at 332.74 125.73 0)
		(mirror y)
		(unit 1)
		(exclude_from_sim no)
		(in_bom yes)
		(on_board yes)
		(dnp no)
		(fields_autoplaced yes)
		(property "Reference" "#PWR0217"
			(at 323.85 128.27 0)
			(effects
				(font
					(size 1.27 1.27)
					(thickness 0.15)
				)
				(justify left bottom)
				(hide yes)
			)
		)
		(property "Value" "GND"
			(at 332.74 130.81 0)
			(effects
				(font
					(size 1.27 1.27)
					(thickness 0.15)
				)
			)
		)
		(property "Footprint" ""
			(at 323.85 133.35 0)
			(effects
				(font
					(size 1.27 1.27)
					(thickness 0.15)
				)
				(justify left bottom)
				(hide yes)
			)
		)
		(property "Datasheet" ""
			(at 323.85 138.43 0)
			(effects
				(font
					(size 1.27 1.27)
					(thickness 0.15)
				)
				(justify left bottom)
				(hide yes)
			)
		)
		(property "Description" ""
			(at 332.74 125.73 0)
			(effects
				(font
					(size 1.27 1.27)
				)
				(hide yes)
			)
		)
		(property "Author" "Antmicro"
			(at 323.85 133.35 0)
			(effects
				(font
					(size 1.27 1.27)
					(thickness 0.15)
				)
				(justify left bottom)
				(hide yes)
			)
		)
		(property "License" "Apache-2.0"
			(at 323.85 135.89 0)
			(effects
				(font
					(size 1.27 1.27)
					(thickness 0.15)
				)
				(justify left bottom)
				(hide yes)
			)
		)
		(pin "1"
		)
		(instances
			(project "polarfire-som"
				(path ""
					(reference "#PWR0217")
					(unit 1)
				)
			)
		)
	)
	(symbol
		(lib_id "antmicropower:GND")
		(at 66.04 255.27 0)
		(unit 1)
		(exclude_from_sim no)
		(in_bom yes)
		(on_board yes)
		(dnp no)
		(property "Reference" "#PWR0287"
			(at 74.93 257.81 0)
			(effects
				(font
					(size 1.27 1.27)
					(thickness 0.15)
				)
				(justify left bottom)
				(hide yes)
			)
		)
		(property "Value" "GND"
			(at 66.04 259.08 0)
			(effects
				(font
					(size 1.27 1.27)
					(thickness 0.15)
				)
			)
		)
		(property "Footprint" ""
			(at 74.93 262.89 0)
			(effects
				(font
					(size 1.27 1.27)
					(thickness 0.15)
				)
				(justify left bottom)
				(hide yes)
			)
		)
		(property "Datasheet" ""
			(at 74.93 267.97 0)
			(effects
				(font
					(size 1.27 1.27)
					(thickness 0.15)
				)
				(justify left bottom)
				(hide yes)
			)
		)
		(property "Description" ""
			(at 66.04 255.27 0)
			(effects
				(font
					(size 1.27 1.27)
				)
				(hide yes)
			)
		)
		(property "Author" "Antmicro"
			(at 74.93 262.89 0)
			(effects
				(font
					(size 1.27 1.27)
					(thickness 0.15)
				)
				(justify left bottom)
				(hide yes)
			)
		)
		(property "License" "Apache-2.0"
			(at 74.93 265.43 0)
			(effects
				(font
					(size 1.27 1.27)
					(thickness 0.15)
				)
				(justify left bottom)
				(hide yes)
			)
		)
		(pin "1"
		)
		(instances
			(project "polarfire-som"
				(path ""
					(reference "#PWR0287")
					(unit 1)
				)
			)
		)
	)
	(symbol
		(lib_id "antmicropower:GND")
		(at 359.41 172.72 0)
		(mirror y)
		(unit 1)
		(exclude_from_sim no)
		(in_bom yes)
		(on_board yes)
		(dnp no)
		(property "Reference" "#PWR0151"
			(at 350.52 175.26 0)
			(effects
				(font
					(size 1.27 1.27)
					(thickness 0.15)
				)
				(justify left bottom)
				(hide yes)
			)
		)
		(property "Value" "GND"
			(at 359.41 176.53 0)
			(effects
				(font
					(size 1.27 1.27)
					(thickness 0.15)
				)
			)
		)
		(property "Footprint" ""
			(at 350.52 180.34 0)
			(effects
				(font
					(size 1.27 1.27)
					(thickness 0.15)
				)
				(justify left bottom)
				(hide yes)
			)
		)
		(property "Datasheet" ""
			(at 350.52 185.42 0)
			(effects
				(font
					(size 1.27 1.27)
					(thickness 0.15)
				)
				(justify left bottom)
				(hide yes)
			)
		)
		(property "Description" ""
			(at 359.41 172.72 0)
			(effects
				(font
					(size 1.27 1.27)
				)
				(hide yes)
			)
		)
		(property "Author" "Antmicro"
			(at 350.52 180.34 0)
			(effects
				(font
					(size 1.27 1.27)
					(thickness 0.15)
				)
				(justify left bottom)
				(hide yes)
			)
		)
		(property "License" "Apache-2.0"
			(at 350.52 182.88 0)
			(effects
				(font
					(size 1.27 1.27)
					(thickness 0.15)
				)
				(justify left bottom)
				(hide yes)
			)
		)
		(pin "1"
		)
		(instances
			(project "polarfire-som"
				(path ""
					(reference "#PWR0151")
					(unit 1)
				)
			)
		)
	)
	(symbol
		(lib_id "antmicroResistors0402:R_590R_0402")
		(at 93.98 232.41 90)
		(unit 1)
		(exclude_from_sim no)
		(in_bom yes)
		(on_board yes)
		(dnp no)
		(fields_autoplaced yes)
		(property "Reference" "R70"
			(at 96.52 228.6 90)
			(effects
				(font
					(size 1.27 1.27)
					(thickness 0.15)
				)
				(justify right)
			)
		)
		(property "Value" "R_590R_0402"
			(at 106.68 212.09 0)
			(effects
				(font
					(size 1.27 1.27)
					(thickness 0.15)
				)
				(justify left bottom)
				(hide yes)
			)
		)
		(property "Footprint" "antmicro-footprints:R_0402_1005Metric"
			(at 109.22 212.09 0)
			(effects
				(font
					(size 1.27 1.27)
					(thickness 0.15)
				)
				(justify left bottom)
				(hide yes)
			)
		)
		(property "Datasheet" "https://www.bourns.com/docs/product-datasheets/cr.pdf"
			(at 111.76 212.09 0)
			(effects
				(font
					(size 1.27 1.27)
					(thickness 0.15)
				)
				(justify left bottom)
				(hide yes)
			)
		)
		(property "Description" "SMD Chip Resistor, 590 ohm, ± 1%, 100 mW, 0402 [1005 Metric], Thick Film, Precision"
			(at 93.98 232.41 0)
			(effects
				(font
					(size 1.27 1.27)
				)
				(hide yes)
			)
		)
		(property "MPN" "CR0402-FX-5900GLF"
			(at 114.3 212.09 0)
			(effects
				(font
					(size 1.27 1.27)
					(thickness 0.15)
				)
				(justify left bottom)
				(hide yes)
			)
		)
		(property "Manufacturer" "Bourns"
			(at 116.84 212.09 0)
			(effects
				(font
					(size 1.27 1.27)
					(thickness 0.15)
				)
				(justify left bottom)
				(hide yes)
			)
		)
		(property "License" "Apache-2.0"
			(at 119.38 212.09 0)
			(effects
				(font
					(size 1.27 1.27)
					(thickness 0.15)
				)
				(justify left bottom)
				(hide yes)
			)
		)
		(property "Author" "Antmicro"
			(at 121.92 212.09 0)
			(effects
				(font
					(size 1.27 1.27)
					(thickness 0.15)
				)
				(justify left bottom)
				(hide yes)
			)
		)
		(property "Val" "590R"
			(at 96.52 231.14 90)
			(effects
				(font
					(size 1.27 1.27)
					(thickness 0.15)
				)
				(justify right)
			)
		)
		(property "Tolerance" "1%"
			(at 104.14 212.09 0)
			(effects
				(font
					(size 1.27 1.27)
				)
				(justify left bottom)
				(hide yes)
			)
		)
		(property "Public" ""
			(at 124.46 212.09 0)
			(effects
				(font
					(size 1.27 1.27)
				)
				(justify left bottom)
				(hide yes)
			)
		)
		(pin "1"
		)
		(pin "2"
		)
		(instances
			(project "polarfire-som"
				(path ""
					(reference "R70")
					(unit 1)
				)
			)
		)
	)
	(symbol
		(lib_id "antmicropower:+3V3")
		(at 332.74 101.6 0)
		(mirror y)
		(unit 1)
		(exclude_from_sim no)
		(in_bom yes)
		(on_board yes)
		(dnp no)
		(fields_autoplaced yes)
		(property "Reference" "#PWR0216"
			(at 317.5 101.6 0)
			(effects
				(font
					(size 1.27 1.27)
					(thickness 0.15)
				)
				(justify left bottom)
				(hide yes)
			)
		)
		(property "Value" "+3V3"
			(at 332.74 96.52 0)
			(effects
				(font
					(size 1.27 1.27)
					(thickness 0.15)
				)
			)
		)
		(property "Footprint" ""
			(at 317.5 109.22 0)
			(effects
				(font
					(size 1.27 1.27)
					(thickness 0.15)
				)
				(justify left bottom)
				(hide yes)
			)
		)
		(property "Datasheet" ""
			(at 317.5 111.76 0)
			(effects
				(font
					(size 1.27 1.27)
					(thickness 0.15)
				)
				(justify left bottom)
				(hide yes)
			)
		)
		(property "Description" ""
			(at 332.74 101.6 0)
			(effects
				(font
					(size 1.27 1.27)
				)
				(hide yes)
			)
		)
		(property "Author" "Antmicro"
			(at 317.5 104.14 0)
			(effects
				(font
					(size 1.27 1.27)
					(thickness 0.15)
				)
				(justify left bottom)
				(hide yes)
			)
		)
		(property "License" "Apache-2.0"
			(at 317.5 106.68 0)
			(effects
				(font
					(size 1.27 1.27)
					(thickness 0.15)
				)
				(justify left bottom)
				(hide yes)
			)
		)
		(pin "1"
		)
		(instances
			(project "polarfire-som"
				(path ""
					(reference "#PWR0216")
					(unit 1)
				)
			)
		)
	)
	(symbol
		(lib_id "antmicropower:+5V")
		(at 66.04 203.2 0)
		(unit 1)
		(exclude_from_sim no)
		(in_bom yes)
		(on_board yes)
		(dnp no)
		(property "Reference" "#PWR0288"
			(at 81.28 205.74 0)
			(effects
				(font
					(size 1.27 1.27)
					(thickness 0.15)
				)
				(justify left bottom)
				(hide yes)
			)
		)
		(property "Value" "+5V"
			(at 66.04 199.39 0)
			(effects
				(font
					(size 1.27 1.27)
					(thickness 0.15)
				)
			)
		)
		(property "Footprint" ""
			(at 81.28 210.82 0)
			(effects
				(font
					(size 1.27 1.27)
					(thickness 0.15)
				)
				(justify left bottom)
				(hide yes)
			)
		)
		(property "Datasheet" ""
			(at 81.28 213.36 0)
			(effects
				(font
					(size 1.27 1.27)
					(thickness 0.15)
				)
				(justify left bottom)
				(hide yes)
			)
		)
		(property "Description" ""
			(at 66.04 203.2 0)
			(effects
				(font
					(size 1.27 1.27)
				)
				(hide yes)
			)
		)
		(property "Author" "Antmicro"
			(at 81.28 210.82 0)
			(effects
				(font
					(size 1.27 1.27)
					(thickness 0.15)
				)
				(justify left bottom)
				(hide yes)
			)
		)
		(property "License" "Apache-2.0"
			(at 81.28 213.36 0)
			(effects
				(font
					(size 1.27 1.27)
					(thickness 0.15)
				)
				(justify left bottom)
				(hide yes)
			)
		)
		(pin "1"
		)
		(instances
			(project "polarfire-som"
				(path ""
					(reference "#PWR0288")
					(unit 1)
				)
			)
		)
	)
	(symbol
		(lib_id "antmicropower:GND")
		(at 330.2 195.58 0)
		(unit 1)
		(exclude_from_sim no)
		(in_bom yes)
		(on_board yes)
		(dnp no)
		(property "Reference" "#PWR0335"
			(at 339.09 198.12 0)
			(effects
				(font
					(size 1.27 1.27)
					(thickness 0.15)
				)
				(justify left bottom)
				(hide yes)
			)
		)
		(property "Value" "GND"
			(at 330.2 199.39 0)
			(effects
				(font
					(size 1.27 1.27)
					(thickness 0.15)
				)
			)
		)
		(property "Footprint" ""
			(at 339.09 203.2 0)
			(effects
				(font
					(size 1.27 1.27)
					(thickness 0.15)
				)
				(justify left bottom)
				(hide yes)
			)
		)
		(property "Datasheet" ""
			(at 339.09 208.28 0)
			(effects
				(font
					(size 1.27 1.27)
					(thickness 0.15)
				)
				(justify left bottom)
				(hide yes)
			)
		)
		(property "Description" ""
			(at 330.2 195.58 0)
			(effects
				(font
					(size 1.27 1.27)
				)
				(hide yes)
			)
		)
		(property "Author" "Antmicro"
			(at 339.09 203.2 0)
			(effects
				(font
					(size 1.27 1.27)
					(thickness 0.15)
				)
				(justify left bottom)
				(hide yes)
			)
		)
		(property "License" "Apache-2.0"
			(at 339.09 205.74 0)
			(effects
				(font
					(size 1.27 1.27)
					(thickness 0.15)
				)
				(justify left bottom)
				(hide yes)
			)
		)
		(pin "1"
		)
		(instances
			(project "polarfire-som"
				(path ""
					(reference "#PWR0335")
					(unit 1)
				)
			)
		)
	)
	(symbol
		(lib_id "antmicroLogicTranslatorsLevelShifters:NTS0102_XSON")
		(at 311.15 52.07 0)
		(unit 1)
		(exclude_from_sim no)
		(in_bom yes)
		(on_board yes)
		(dnp no)
		(fields_autoplaced yes)
		(property "Reference" "U20"
			(at 321.31 44.45 0)
			(effects
				(font
					(size 1.27 1.27)
					(thickness 0.15)
				)
			)
		)
		(property "Value" "NTS0102_XSON"
			(at 346.71 59.69 0)
			(effects
				(font
					(size 1.27 1.27)
					(thickness 0.15)
				)
				(justify left bottom)
				(hide yes)
			)
		)
		(property "Footprint" "antmicro-footprints:XSON-8_1x1.95mm_P0.5mm"
			(at 346.71 62.23 0)
			(effects
				(font
					(size 1.27 1.27)
					(thickness 0.15)
				)
				(justify left bottom)
				(hide yes)
			)
		)
		(property "Datasheet" "http://www.farnell.com/datasheets/1760723.pdf"
			(at 346.71 64.77 0)
			(effects
				(font
					(size 1.27 1.27)
					(thickness 0.15)
				)
				(justify left bottom)
				(hide yes)
			)
		)
		(property "Description" "Transceiver, 1.65 V to 3.6 V, XSON-8"
			(at 311.15 52.07 0)
			(effects
				(font
					(size 1.27 1.27)
				)
				(hide yes)
			)
		)
		(property "MPN" "NTS0102GT"
			(at 321.31 46.99 0)
			(effects
				(font
					(size 1.27 1.27)
					(thickness 0.15)
				)
			)
		)
		(property "Manufacturer" "NXP"
			(at 346.71 67.31 0)
			(effects
				(font
					(size 1.27 1.27)
					(thickness 0.15)
				)
				(justify left bottom)
				(hide yes)
			)
		)
		(property "Author" "Antmicro"
			(at 346.71 69.85 0)
			(effects
				(font
					(size 1.27 1.27)
					(thickness 0.15)
				)
				(justify left bottom)
				(hide yes)
			)
		)
		(property "License" "Apache-2.0"
			(at 346.71 72.39 0)
			(effects
				(font
					(size 1.27 1.27)
					(thickness 0.15)
				)
				(justify left bottom)
				(hide yes)
			)
		)
		(pin "2"
		)
		(pin "6"
		)
		(pin "7"
		)
		(pin "5"
		)
		(pin "4"
		)
		(pin "3"
		)
		(pin "1"
		)
		(pin "8"
		)
		(instances
			(project "polarfire-som"
				(path ""
					(reference "U20")
					(unit 1)
				)
			)
		)
	)
	(symbol
		(lib_id "antmicroCapacitors0402:C_100n_0402")
		(at 185.42 226.06 90)
		(mirror x)
		(unit 1)
		(exclude_from_sim no)
		(in_bom yes)
		(on_board yes)
		(dnp no)
		(property "Reference" "C81"
			(at 181.61 226.06 90)
			(effects
				(font
					(size 1.27 1.27)
					(thickness 0.15)
				)
			)
		)
		(property "Value" "C_100n_0402"
			(at 195.58 246.38 0)
			(effects
				(font
					(size 1.27 1.27)
					(thickness 0.15)
				)
				(justify left bottom)
				(hide yes)
			)
		)
		(property "Footprint" "antmicro-footprints:C_0402_1005Metric"
			(at 198.12 246.38 0)
			(effects
				(font
					(size 1.27 1.27)
					(thickness 0.15)
				)
				(justify left bottom)
				(hide yes)
			)
		)
		(property "Datasheet" "https://www.murata.com/products/productdetail?partno=GRM155R61H104KE14%23"
			(at 200.66 246.38 0)
			(effects
				(font
					(size 1.27 1.27)
					(thickness 0.15)
				)
				(justify left bottom)
				(hide yes)
			)
		)
		(property "Description" "SMD Multilayer Ceramic Capacitor, 0.1 µF, 50 V, 0402 [1005 Metric], ± 10%, X5R, GRM Series"
			(at 185.42 226.06 0)
			(effects
				(font
					(size 1.27 1.27)
				)
				(hide yes)
			)
		)
		(property "MPN" "GRM155R61H104KE14D"
			(at 203.2 246.38 0)
			(effects
				(font
					(size 1.27 1.27)
					(thickness 0.15)
				)
				(justify left bottom)
				(hide yes)
			)
		)
		(property "Manufacturer" "Murata"
			(at 205.74 246.38 0)
			(effects
				(font
					(size 1.27 1.27)
					(thickness 0.15)
				)
				(justify left bottom)
				(hide yes)
			)
		)
		(property "License" "Apache-2.0"
			(at 208.28 246.38 0)
			(effects
				(font
					(size 1.27 1.27)
					(thickness 0.15)
				)
				(justify left bottom)
				(hide yes)
			)
		)
		(property "Author" "Antmicro"
			(at 210.82 246.38 0)
			(effects
				(font
					(size 1.27 1.27)
					(thickness 0.15)
				)
				(justify left bottom)
				(hide yes)
			)
		)
		(property "Val" "100n"
			(at 184.15 231.14 90)
			(effects
				(font
					(size 1.27 1.27)
					(thickness 0.15)
				)
				(justify left bottom)
			)
		)
		(property "Voltage" "50V"
			(at 213.36 246.38 0)
			(effects
				(font
					(size 1.27 1.27)
				)
				(justify left bottom)
				(hide yes)
			)
		)
		(property "Dielectric" "X5R"
			(at 215.9 246.38 0)
			(effects
				(font
					(size 1.27 1.27)
				)
				(justify left bottom)
				(hide yes)
			)
		)
		(property "Public" ""
			(at 218.44 246.38 0)
			(effects
				(font
					(size 1.27 1.27)
				)
				(justify left bottom)
				(hide yes)
			)
		)
		(pin "2"
		)
		(pin "1"
		)
		(instances
			(project "polarfire-som"
				(path ""
					(reference "C81")
					(unit 1)
				)
			)
		)
	)
	(symbol
		(lib_id "antmicroLogicTranslatorsLevelShifters:74LVC1T45GM")
		(at 312.42 189.23 0)
		(unit 1)
		(exclude_from_sim no)
		(in_bom yes)
		(on_board yes)
		(dnp no)
		(fields_autoplaced yes)
		(property "Reference" "U18"
			(at 320.675 182.88 0)
			(effects
				(font
					(size 1.27 1.27)
					(thickness 0.15)
				)
			)
		)
		(property "Value" "74LVC1T45GM"
			(at 320.675 185.42 0)
			(effects
				(font
					(size 1.27 1.27)
					(thickness 0.15)
				)
			)
		)
		(property "Footprint" "antmicro-footprints:SOT-886"
			(at 342.9 199.39 0)
			(effects
				(font
					(size 1.27 1.27)
					(thickness 0.15)
				)
				(justify left bottom)
				(hide yes)
			)
		)
		(property "Datasheet" "http://www.ti.com/general/docs/suppproductinfo.tsp?distId=10&gotoUrl=http%3A%2F%2Fwww.ti.com%2Flit%2Fgpn%2Fsn74lvc1t45"
			(at 342.9 201.93 0)
			(effects
				(font
					(size 1.27 1.27)
					(thickness 0.15)
				)
				(justify left bottom)
				(hide yes)
			)
		)
		(property "Description" "Transceiver, Translating, 74LVC1T45, 74LVC Family, 1.2V to 5.5V Supply, XSON-6"
			(at 312.42 189.23 0)
			(effects
				(font
					(size 1.27 1.27)
				)
				(hide yes)
			)
		)
		(property "MPN" "74LVC1T45GM-Q100X"
			(at 342.9 204.47 0)
			(effects
				(font
					(size 1.27 1.27)
					(thickness 0.15)
				)
				(justify left bottom)
				(hide yes)
			)
		)
		(property "Manufacturer" "Nexperia"
			(at 342.9 207.01 0)
			(effects
				(font
					(size 1.27 1.27)
					(thickness 0.15)
				)
				(justify left bottom)
				(hide yes)
			)
		)
		(property "Author" "Antmicro"
			(at 342.9 209.55 0)
			(effects
				(font
					(size 1.27 1.27)
					(thickness 0.15)
				)
				(justify left bottom)
				(hide yes)
			)
		)
		(property "License" "Apache-2.0"
			(at 342.9 212.09 0)
			(effects
				(font
					(size 1.27 1.27)
					(thickness 0.15)
				)
				(justify left bottom)
				(hide yes)
			)
		)
		(pin "5"
		)
		(pin "1"
		)
		(pin "4"
		)
		(pin "3"
		)
		(pin "6"
		)
		(pin "2"
		)
		(instances
			(project "polarfire-som"
				(path ""
					(reference "U18")
					(unit 1)
				)
			)
		)
	)
	(symbol
		(lib_id "antmicropower:GND")
		(at 304.8 48.26 0)
		(mirror y)
		(unit 1)
		(exclude_from_sim no)
		(in_bom yes)
		(on_board yes)
		(dnp no)
		(property "Reference" "#PWR045"
			(at 295.91 50.8 0)
			(effects
				(font
					(size 1.27 1.27)
					(thickness 0.15)
				)
				(justify left bottom)
				(hide yes)
			)
		)
		(property "Value" "GND"
			(at 300.99 49.53 0)
			(effects
				(font
					(size 1.27 1.27)
					(thickness 0.15)
				)
			)
		)
		(property "Footprint" ""
			(at 295.91 55.88 0)
			(effects
				(font
					(size 1.27 1.27)
					(thickness 0.15)
				)
				(justify left bottom)
				(hide yes)
			)
		)
		(property "Datasheet" ""
			(at 295.91 60.96 0)
			(effects
				(font
					(size 1.27 1.27)
					(thickness 0.15)
				)
				(justify left bottom)
				(hide yes)
			)
		)
		(property "Description" ""
			(at 304.8 48.26 0)
			(effects
				(font
					(size 1.27 1.27)
				)
				(hide yes)
			)
		)
		(property "Author" "Antmicro"
			(at 295.91 55.88 0)
			(effects
				(font
					(size 1.27 1.27)
					(thickness 0.15)
				)
				(justify left bottom)
				(hide yes)
			)
		)
		(property "License" "Apache-2.0"
			(at 295.91 58.42 0)
			(effects
				(font
					(size 1.27 1.27)
					(thickness 0.15)
				)
				(justify left bottom)
				(hide yes)
			)
		)
		(pin "1"
		)
		(instances
			(project "polarfire-som"
				(path ""
					(reference "#PWR045")
					(unit 1)
				)
			)
		)
	)
	(symbol
		(lib_id "antmicroFPGAChips:MPFS250T-FCVG484E")
		(at 76.2 48.26 0)
		(unit 2)
		(exclude_from_sim no)
		(in_bom yes)
		(on_board yes)
		(dnp no)
		(fields_autoplaced yes)
		(property "Reference" "U1"
			(at 121.92 38.1 0)
			(effects
				(font
					(size 1.27 1.27)
					(thickness 0.15)
				)
			)
		)
		(property "Value" "MPFS250T-FCVG484"
			(at 181.61 53.34 0)
			(effects
				(font
					(size 1.27 1.27)
					(thickness 0.15)
				)
				(justify left bottom)
				(hide yes)
			)
		)
		(property "Footprint" "antmicro-footprints:BGA-484_19x19mm_Layout22x22_P0.8mm_FCVG484"
			(at 181.61 55.88 0)
			(effects
				(font
					(size 1.27 1.27)
					(thickness 0.15)
				)
				(justify left bottom)
				(hide yes)
			)
		)
		(property "Datasheet" "https://ww1.microchip.com/downloads/aemDocuments/documents/FPGA/ProductDocuments/DataSheets/PolarFire-SoC-Datasheet-DS00004248.pdf"
			(at 181.61 58.42 0)
			(effects
				(font
					(size 1.27 1.27)
					(thickness 0.15)
				)
				(justify left bottom)
				(hide yes)
			)
		)
		(property "Description" "RISC-V System On Chip (SOC) IC PolarFire® FPGA - 254K Logic Modules 484-FCBGA (19x19)"
			(at 181.61 68.58 0)
			(effects
				(font
					(size 1.27 1.27)
				)
				(justify left bottom)
				(hide yes)
			)
		)
		(property "MPN" "MPFS250T-FCVG484E"
			(at 121.92 40.64 0)
			(effects
				(font
					(size 1.27 1.27)
					(thickness 0.15)
				)
			)
		)
		(property "Manufacturer" "Microchip Technology"
			(at 181.61 60.96 0)
			(effects
				(font
					(size 1.27 1.27)
					(thickness 0.15)
				)
				(justify left bottom)
				(hide yes)
			)
		)
		(property "VSD_class" "MPFS250T"
			(at 180.34 66.04 0)
			(effects
				(font
					(size 1.27 1.27)
					(thickness 0.15)
				)
				(justify left bottom)
				(hide yes)
			)
		)
		(property "Author" "Antmicro"
			(at 181.61 63.5 0)
			(effects
				(font
					(size 1.27 1.27)
					(thickness 0.15)
				)
				(justify left bottom)
				(hide yes)
			)
		)
		(property "License" "Apache-2.0"
			(at 181.61 66.04 0)
			(effects
				(font
					(size 1.27 1.27)
					(thickness 0.15)
				)
				(justify left bottom)
				(hide yes)
			)
		)
		(pin "AA12"
		)
		(pin "AA13"
		)
		(pin "AA15"
		)
		(pin "AA16"
		)
		(pin "AA17"
		)
		(pin "AA18"
		)
		(pin "AA20"
		)
		(pin "AA21"
		)
		(pin "AA22"
		)
		(pin "AB12"
		)
		(pin "AB13"
		)
		(pin "AB14"
		)
		(pin "AB15"
		)
		(pin "AB17"
		)
		(pin "AB18"
		)
		(pin "AB19"
		)
		(pin "AB20"
		)
		(pin "AB21"
		)
		(pin "R12"
		)
		(pin "R14"
		)
		(pin "R15"
		)
		(pin "R16"
		)
		(pin "T12"
		)
		(pin "T13"
		)
		(pin "T15"
		)
		(pin "T16"
		)
		(pin "T17"
		)
		(pin "U12"
		)
		(pin "U13"
		)
		(pin "U14"
		)
		(pin "U15"
		)
		(pin "U17"
		)
		(pin "U18"
		)
		(pin "U19"
		)
		(pin "V12"
		)
		(pin "V14"
		)
		(pin "V15"
		)
		(pin "V16"
		)
		(pin "V17"
		)
		(pin "V19"
		)
		(pin "V20"
		)
		(pin "V21"
		)
		(pin "V22"
		)
		(pin "W12"
		)
		(pin "W13"
		)
		(pin "W14"
		)
		(pin "W16"
		)
		(pin "W17"
		)
		(pin "W18"
		)
		(pin "W19"
		)
		(pin "W21"
		)
		(pin "W22"
		)
		(pin "Y13"
		)
		(pin "Y14"
		)
		(pin "Y15"
		)
		(pin "Y16"
		)
		(pin "Y18"
		)
		(pin "Y19"
		)
		(pin "Y20"
		)
		(pin "Y21"
		)
		(pin "A10"
		)
		(pin "A11"
		)
		(pin "A12"
		)
		(pin "A13"
		)
		(pin "A15"
		)
		(pin "A16"
		)
		(pin "A17"
		)
		(pin "A18"
		)
		(pin "A20"
		)
		(pin "A21"
		)
		(pin "A5"
		)
		(pin "A6"
		)
		(pin "A7"
		)
		(pin "A8"
		)
		(pin "B10"
		)
		(pin "B12"
		)
		(pin "B13"
		)
		(pin "B14"
		)
		(pin "B15"
		)
		(pin "B17"
		)
		(pin "B18"
		)
		(pin "B19"
		)
		(pin "B20"
		)
		(pin "B21"
		)
		(pin "B22"
		)
		(pin "B4"
		)
		(pin "B5"
		)
		(pin "B7"
		)
		(pin "B8"
		)
		(pin "B9"
		)
		(pin "C10"
		)
		(pin "C11"
		)
		(pin "C12"
		)
		(pin "C14"
		)
		(pin "C15"
		)
		(pin "C16"
		)
		(pin "C17"
		)
		(pin "C19"
		)
		(pin "C20"
		)
		(pin "C22"
		)
		(pin "C4"
		)
		(pin "C5"
		)
		(pin "C6"
		)
		(pin "C7"
		)
		(pin "C9"
		)
		(pin "D11"
		)
		(pin "D12"
		)
		(pin "D13"
		)
		(pin "D14"
		)
		(pin "D16"
		)
		(pin "D17"
		)
		(pin "D18"
		)
		(pin "D19"
		)
		(pin "D20"
		)
		(pin "D21"
		)
		(pin "D22"
		)
		(pin "D6"
		)
		(pin "D7"
		)
		(pin "D8"
		)
		(pin "D9"
		)
		(pin "E10"
		)
		(pin "E11"
		)
		(pin "E13"
		)
		(pin "E14"
		)
		(pin "E15"
		)
		(pin "E16"
		)
		(pin "E18"
		)
		(pin "E19"
		)
		(pin "F10"
		)
		(pin "F11"
		)
		(pin "F12"
		)
		(pin "F13"
		)
		(pin "F15"
		)
		(pin "F16"
		)
		(pin "F17"
		)
		(pin "G12"
		)
		(pin "G13"
		)
		(pin "G14"
		)
		(pin "G15"
		)
		(pin "G17"
		)
		(pin "H12"
		)
		(pin "H13"
		)
		(pin "H15"
		)
		(pin "H17"
		)
		(pin "A2"
		)
		(pin "A3"
		)
		(pin "B1"
		)
		(pin "B2"
		)
		(pin "B3"
		)
		(pin "C1"
		)
		(pin "C2"
		)
		(pin "D1"
		)
		(pin "D2"
		)
		(pin "D3"
		)
		(pin "D4"
		)
		(pin "E1"
		)
		(pin "E3"
		)
		(pin "E4"
		)
		(pin "E5"
		)
		(pin "F1"
		)
		(pin "F2"
		)
		(pin "F3"
		)
		(pin "F5"
		)
		(pin "F6"
		)
		(pin "G2"
		)
		(pin "G3"
		)
		(pin "G4"
		)
		(pin "G5"
		)
		(pin "E6"
		)
		(pin "E8"
		)
		(pin "E9"
		)
		(pin "F7"
		)
		(pin "F8"
		)
		(pin "G10"
		)
		(pin "G7"
		)
		(pin "G8"
		)
		(pin "G9"
		)
		(pin "H10"
		)
		(pin "H11"
		)
		(pin "H7"
		)
		(pin "H9"
		)
		(pin "H1"
		)
		(pin "H2"
		)
		(pin "H4"
		)
		(pin "H5"
		)
		(pin "H6"
		)
		(pin "J1"
		)
		(pin "J2"
		)
		(pin "J3"
		)
		(pin "J4"
		)
		(pin "J6"
		)
		(pin "J7"
		)
		(pin "K3"
		)
		(pin "K4"
		)
		(pin "K5"
		)
		(pin "K6"
		)
		(pin "K7"
		)
		(pin "L5"
		)
		(pin "L6"
		)
		(pin "L7"
		)
		(pin "L8"
		)
		(pin "M7"
		)
		(pin "N6"
		)
		(pin "N7"
		)
		(pin "N8"
		)
		(pin "AA1"
		)
		(pin "AA10"
		)
		(pin "AA11"
		)
		(pin "AA2"
		)
		(pin "AA3"
		)
		(pin "AA5"
		)
		(pin "AA6"
		)
		(pin "AA7"
		)
		(pin "AA8"
		)
		(pin "AB10"
		)
		(pin "AB2"
		)
		(pin "AB3"
		)
		(pin "AB4"
		)
		(pin "AB5"
		)
		(pin "AB7"
		)
		(pin "AB8"
		)
		(pin "AB9"
		)
		(pin "K1"
		)
		(pin "L1"
		)
		(pin "L2"
		)
		(pin "L3"
		)
		(pin "M2"
		)
		(pin "M3"
		)
		(pin "M4"
		)
		(pin "M5"
		)
		(pin "N1"
		)
		(pin "N2"
		)
		(pin "N4"
		)
		(pin "N5"
		)
		(pin "P1"
		)
		(pin "P2"
		)
		(pin "P3"
		)
		(pin "P4"
		)
		(pin "P6"
		)
		(pin "P7"
		)
		(pin "P8"
		)
		(pin "R1"
		)
		(pin "R10"
		)
		(pin "R11"
		)
		(pin "R3"
		)
		(pin "R4"
		)
		(pin "R5"
		)
		(pin "R6"
		)
		(pin "R8"
		)
		(pin "T1"
		)
		(pin "T10"
		)
		(pin "T11"
		)
		(pin "T2"
		)
		(pin "T3"
		)
		(pin "T5"
		)
		(pin "T6"
		)
		(pin "T7"
		)
		(pin "T8"
		)
		(pin "U10"
		)
		(pin "U2"
		)
		(pin "U3"
		)
		(pin "U4"
		)
		(pin "U5"
		)
		(pin "U7"
		)
		(pin "U8"
		)
		(pin "U9"
		)
		(pin "V1"
		)
		(pin "V10"
		)
		(pin "V11"
		)
		(pin "V2"
		)
		(pin "V4"
		)
		(pin "V5"
		)
		(pin "V6"
		)
		(pin "V7"
		)
		(pin "V9"
		)
		(pin "W1"
		)
		(pin "W11"
		)
		(pin "W2"
		)
		(pin "W3"
		)
		(pin "W4"
		)
		(pin "W6"
		)
		(pin "W7"
		)
		(pin "W8"
		)
		(pin "W9"
		)
		(pin "Y1"
		)
		(pin "Y10"
		)
		(pin "Y11"
		)
		(pin "Y3"
		)
		(pin "Y4"
		)
		(pin "Y5"
		)
		(pin "Y6"
		)
		(pin "Y8"
		)
		(pin "Y9"
		)
		(pin "F21"
		)
		(pin "F22"
		)
		(pin "G19"
		)
		(pin "G20"
		)
		(pin "H21"
		)
		(pin "H22"
		)
		(pin "J19"
		)
		(pin "J20"
		)
		(pin "K21"
		)
		(pin "K22"
		)
		(pin "L19"
		)
		(pin "L20"
		)
		(pin "M21"
		)
		(pin "M22"
		)
		(pin "N19"
		)
		(pin "N20"
		)
		(pin "P21"
		)
		(pin "P22"
		)
		(pin "R19"
		)
		(pin "R20"
		)
		(pin "T21"
		)
		(pin "T22"
		)
		(pin "A1"
		)
		(pin "A14"
		)
		(pin "A19"
		)
		(pin "A22"
		)
		(pin "A4"
		)
		(pin "A9"
		)
		(pin "AA14"
		)
		(pin "AA19"
		)
		(pin "AA4"
		)
		(pin "AA9"
		)
		(pin "AB1"
		)
		(pin "AB11"
		)
		(pin "AB16"
		)
		(pin "AB22"
		)
		(pin "AB6"
		)
		(pin "B11"
		)
		(pin "B16"
		)
		(pin "B6"
		)
		(pin "C13"
		)
		(pin "C18"
		)
		(pin "C21"
		)
		(pin "C3"
		)
		(pin "C8"
		)
		(pin "D10"
		)
		(pin "D15"
		)
		(pin "D5"
		)
		(pin "E12"
		)
		(pin "E17"
		)
		(pin "E2"
		)
		(pin "E20"
		)
		(pin "E21"
		)
		(pin "E22"
		)
		(pin "E7"
		)
		(pin "F14"
		)
		(pin "F18"
		)
		(pin "F19"
		)
		(pin "F20"
		)
		(pin "F4"
		)
		(pin "F9"
		)
		(pin "G1"
		)
		(pin "G11"
		)
		(pin "G16"
		)
		(pin "G18"
		)
		(pin "G21"
		)
		(pin "G22"
		)
		(pin "G6"
		)
		(pin "H14"
		)
		(pin "H16"
		)
		(pin "H18"
		)
		(pin "H19"
		)
		(pin "H20"
		)
		(pin "H3"
		)
		(pin "H8"
		)
		(pin "J10"
		)
		(pin "J11"
		)
		(pin "J12"
		)
		(pin "J13"
		)
		(pin "J14"
		)
		(pin "J15"
		)
		(pin "J16"
		)
		(pin "J17"
		)
		(pin "J18"
		)
		(pin "J21"
		)
		(pin "J22"
		)
		(pin "J5"
		)
		(pin "J8"
		)
		(pin "J9"
		)
		(pin "K10"
		)
		(pin "K11"
		)
		(pin "K12"
		)
		(pin "K13"
		)
		(pin "K14"
		)
		(pin "K15"
		)
		(pin "K16"
		)
		(pin "K17"
		)
		(pin "K18"
		)
		(pin "K19"
		)
		(pin "K2"
		)
		(pin "K20"
		)
		(pin "K8"
		)
		(pin "K9"
		)
		(pin "L10"
		)
		(pin "L11"
		)
		(pin "L12"
		)
		(pin "L13"
		)
		(pin "L14"
		)
		(pin "L15"
		)
		(pin "L16"
		)
		(pin "L17"
		)
		(pin "L18"
		)
		(pin "L21"
		)
		(pin "L22"
		)
		(pin "L4"
		)
		(pin "L9"
		)
		(pin "M1"
		)
		(pin "M10"
		)
		(pin "M11"
		)
		(pin "M12"
		)
		(pin "M13"
		)
		(pin "M14"
		)
		(pin "M15"
		)
		(pin "M16"
		)
		(pin "M17"
		)
		(pin "M18"
		)
		(pin "M19"
		)
		(pin "M20"
		)
		(pin "M6"
		)
		(pin "M8"
		)
		(pin "M9"
		)
		(pin "N10"
		)
		(pin "N11"
		)
		(pin "N12"
		)
		(pin "N13"
		)
		(pin "N14"
		)
		(pin "N15"
		)
		(pin "N16"
		)
		(pin "N17"
		)
		(pin "N18"
		)
		(pin "N21"
		)
		(pin "N22"
		)
		(pin "N3"
		)
		(pin "N9"
		)
		(pin "P10"
		)
		(pin "P11"
		)
		(pin "P12"
		)
		(pin "P13"
		)
		(pin "P14"
		)
		(pin "P15"
		)
		(pin "P16"
		)
		(pin "P17"
		)
		(pin "P18"
		)
		(pin "P19"
		)
		(pin "P20"
		)
		(pin "P5"
		)
		(pin "P9"
		)
		(pin "R13"
		)
		(pin "R17"
		)
		(pin "R18"
		)
		(pin "R2"
		)
		(pin "R21"
		)
		(pin "R22"
		)
		(pin "R7"
		)
		(pin "R9"
		)
		(pin "T14"
		)
		(pin "T18"
		)
		(pin "T19"
		)
		(pin "T20"
		)
		(pin "T4"
		)
		(pin "T9"
		)
		(pin "U1"
		)
		(pin "U11"
		)
		(pin "U16"
		)
		(pin "U20"
		)
		(pin "U21"
		)
		(pin "U22"
		)
		(pin "U6"
		)
		(pin "V13"
		)
		(pin "V18"
		)
		(pin "V3"
		)
		(pin "V8"
		)
		(pin "W10"
		)
		(pin "W15"
		)
		(pin "W20"
		)
		(pin "W5"
		)
		(pin "Y12"
		)
		(pin "Y17"
		)
		(pin "Y2"
		)
		(pin "Y22"
		)
		(pin "Y7"
		)
		(instances
			(project "polarfire-som"
				(path ""
					(reference "U1")
					(unit 2)
				)
			)
		)
	)
	(symbol
		(lib_id "antmicropower:VDDI")
		(at 367.03 222.25 0)
		(unit 1)
		(exclude_from_sim no)
		(in_bom yes)
		(on_board yes)
		(dnp no)
		(fields_autoplaced yes)
		(property "Reference" "#PWR0295"
			(at 367.03 226.06 0)
			(effects
				(font
					(size 1.27 1.27)
				)
				(hide yes)
			)
		)
		(property "Value" "VDD"
			(at 367.03 217.805 0)
			(effects
				(font
					(size 1.27 1.27)
				)
			)
		)
		(property "Footprint" ""
			(at 367.03 222.25 0)
			(effects
				(font
					(size 1.27 1.27)
				)
				(hide yes)
			)
		)
		(property "Datasheet" ""
			(at 367.03 222.25 0)
			(effects
				(font
					(size 1.27 1.27)
				)
				(hide yes)
			)
		)
		(property "Description" ""
			(at 367.03 222.25 0)
			(effects
				(font
					(size 1.27 1.27)
				)
				(hide yes)
			)
		)
		(pin "1"
		)
		(instances
			(project "polarfire-som"
				(path ""
					(reference "#PWR0295")
					(unit 1)
				)
			)
		)
	)
	(symbol
		(lib_id "antmicroCapacitors0402:C_100n_0402")
		(at 365.76 166.37 270)
		(unit 1)
		(exclude_from_sim no)
		(in_bom yes)
		(on_board yes)
		(dnp no)
		(property "Reference" "C218"
			(at 369.57 166.37 90)
			(effects
				(font
					(size 1.27 1.27)
					(thickness 0.15)
				)
			)
		)
		(property "Value" "C_100n_0402"
			(at 355.6 186.69 0)
			(effects
				(font
					(size 1.27 1.27)
					(thickness 0.15)
				)
				(justify left bottom)
				(hide yes)
			)
		)
		(property "Footprint" "antmicro-footprints:C_0402_1005Metric"
			(at 353.06 186.69 0)
			(effects
				(font
					(size 1.27 1.27)
					(thickness 0.15)
				)
				(justify left bottom)
				(hide yes)
			)
		)
		(property "Datasheet" "https://www.murata.com/products/productdetail?partno=GRM155R61H104KE14%23"
			(at 350.52 186.69 0)
			(effects
				(font
					(size 1.27 1.27)
					(thickness 0.15)
				)
				(justify left bottom)
				(hide yes)
			)
		)
		(property "Description" "SMD Multilayer Ceramic Capacitor, 0.1 µF, 50 V, 0402 [1005 Metric], ± 10%, X5R, GRM Series"
			(at 365.76 166.37 0)
			(effects
				(font
					(size 1.27 1.27)
				)
				(hide yes)
			)
		)
		(property "MPN" "GRM155R61H104KE14D"
			(at 347.98 186.69 0)
			(effects
				(font
					(size 1.27 1.27)
					(thickness 0.15)
				)
				(justify left bottom)
				(hide yes)
			)
		)
		(property "Manufacturer" "Murata"
			(at 345.44 186.69 0)
			(effects
				(font
					(size 1.27 1.27)
					(thickness 0.15)
				)
				(justify left bottom)
				(hide yes)
			)
		)
		(property "License" "Apache-2.0"
			(at 342.9 186.69 0)
			(effects
				(font
					(size 1.27 1.27)
					(thickness 0.15)
				)
				(justify left bottom)
				(hide yes)
			)
		)
		(property "Author" "Antmicro"
			(at 340.36 186.69 0)
			(effects
				(font
					(size 1.27 1.27)
					(thickness 0.15)
				)
				(justify left bottom)
				(hide yes)
			)
		)
		(property "Val" "100n"
			(at 367.03 171.45 90)
			(effects
				(font
					(size 1.27 1.27)
					(thickness 0.15)
				)
				(justify left bottom)
			)
		)
		(property "Voltage" "50V"
			(at 337.82 186.69 0)
			(effects
				(font
					(size 1.27 1.27)
				)
				(justify left bottom)
				(hide yes)
			)
		)
		(property "Dielectric" "X5R"
			(at 335.28 186.69 0)
			(effects
				(font
					(size 1.27 1.27)
				)
				(justify left bottom)
				(hide yes)
			)
		)
		(property "Public" ""
			(at 332.74 186.69 0)
			(effects
				(font
					(size 1.27 1.27)
				)
				(justify left bottom)
				(hide yes)
			)
		)
		(pin "2"
		)
		(pin "1"
		)
		(instances
			(project "polarfire-som"
				(path ""
					(reference "C218")
					(unit 1)
				)
			)
		)
	)
	(symbol
		(lib_id "antmicropower:GND")
		(at 367.03 229.87 0)
		(mirror y)
		(unit 1)
		(exclude_from_sim no)
		(in_bom yes)
		(on_board yes)
		(dnp no)
		(property "Reference" "#PWR0303"
			(at 358.14 232.41 0)
			(effects
				(font
					(size 1.27 1.27)
					(thickness 0.15)
				)
				(justify left bottom)
				(hide yes)
			)
		)
		(property "Value" "GND"
			(at 367.03 233.68 0)
			(effects
				(font
					(size 1.27 1.27)
					(thickness 0.15)
				)
			)
		)
		(property "Footprint" ""
			(at 358.14 237.49 0)
			(effects
				(font
					(size 1.27 1.27)
					(thickness 0.15)
				)
				(justify left bottom)
				(hide yes)
			)
		)
		(property "Datasheet" ""
			(at 358.14 242.57 0)
			(effects
				(font
					(size 1.27 1.27)
					(thickness 0.15)
				)
				(justify left bottom)
				(hide yes)
			)
		)
		(property "Description" ""
			(at 367.03 229.87 0)
			(effects
				(font
					(size 1.27 1.27)
				)
				(hide yes)
			)
		)
		(property "Author" "Antmicro"
			(at 358.14 237.49 0)
			(effects
				(font
					(size 1.27 1.27)
					(thickness 0.15)
				)
				(justify left bottom)
				(hide yes)
			)
		)
		(property "License" "Apache-2.0"
			(at 358.14 240.03 0)
			(effects
				(font
					(size 1.27 1.27)
					(thickness 0.15)
				)
				(justify left bottom)
				(hide yes)
			)
		)
		(pin "1"
		)
		(instances
			(project "polarfire-som"
				(path ""
					(reference "#PWR0303")
					(unit 1)
				)
			)
		)
	)
	(symbol
		(lib_id "antmicropower:+3V3")
		(at 156.21 203.2 0)
		(mirror y)
		(unit 1)
		(exclude_from_sim no)
		(in_bom yes)
		(on_board yes)
		(dnp no)
		(fields_autoplaced yes)
		(property "Reference" "#PWR0316"
			(at 140.97 203.2 0)
			(effects
				(font
					(size 1.27 1.27)
					(thickness 0.15)
				)
				(justify left bottom)
				(hide yes)
			)
		)
		(property "Value" "+3V3"
			(at 156.21 198.12 0)
			(effects
				(font
					(size 1.27 1.27)
					(thickness 0.15)
				)
			)
		)
		(property "Footprint" ""
			(at 140.97 210.82 0)
			(effects
				(font
					(size 1.27 1.27)
					(thickness 0.15)
				)
				(justify left bottom)
				(hide yes)
			)
		)
		(property "Datasheet" ""
			(at 140.97 213.36 0)
			(effects
				(font
					(size 1.27 1.27)
					(thickness 0.15)
				)
				(justify left bottom)
				(hide yes)
			)
		)
		(property "Description" ""
			(at 156.21 203.2 0)
			(effects
				(font
					(size 1.27 1.27)
				)
				(hide yes)
			)
		)
		(property "Author" "Antmicro"
			(at 140.97 205.74 0)
			(effects
				(font
					(size 1.27 1.27)
					(thickness 0.15)
				)
				(justify left bottom)
				(hide yes)
			)
		)
		(property "License" "Apache-2.0"
			(at 140.97 208.28 0)
			(effects
				(font
					(size 1.27 1.27)
					(thickness 0.15)
				)
				(justify left bottom)
				(hide yes)
			)
		)
		(pin "1"
		)
		(instances
			(project "polarfire-som"
				(path ""
					(reference "#PWR0316")
					(unit 1)
				)
			)
		)
	)
	(symbol
		(lib_id "antmicropower:GND")
		(at 365.76 172.72 0)
		(unit 1)
		(exclude_from_sim no)
		(in_bom yes)
		(on_board yes)
		(dnp no)
		(property "Reference" "#PWR0154"
			(at 374.65 175.26 0)
			(effects
				(font
					(size 1.27 1.27)
					(thickness 0.15)
				)
				(justify left bottom)
				(hide yes)
			)
		)
		(property "Value" "GND"
			(at 365.76 176.53 0)
			(effects
				(font
					(size 1.27 1.27)
					(thickness 0.15)
				)
			)
		)
		(property "Footprint" ""
			(at 374.65 180.34 0)
			(effects
				(font
					(size 1.27 1.27)
					(thickness 0.15)
				)
				(justify left bottom)
				(hide yes)
			)
		)
		(property "Datasheet" ""
			(at 374.65 185.42 0)
			(effects
				(font
					(size 1.27 1.27)
					(thickness 0.15)
				)
				(justify left bottom)
				(hide yes)
			)
		)
		(property "Description" ""
			(at 365.76 172.72 0)
			(effects
				(font
					(size 1.27 1.27)
				)
				(hide yes)
			)
		)
		(property "Author" "Antmicro"
			(at 374.65 180.34 0)
			(effects
				(font
					(size 1.27 1.27)
					(thickness 0.15)
				)
				(justify left bottom)
				(hide yes)
			)
		)
		(property "License" "Apache-2.0"
			(at 374.65 182.88 0)
			(effects
				(font
					(size 1.27 1.27)
					(thickness 0.15)
				)
				(justify left bottom)
				(hide yes)
			)
		)
		(pin "1"
		)
		(instances
			(project "polarfire-som"
				(path ""
					(reference "#PWR0154")
					(unit 1)
				)
			)
		)
	)
	(symbol
		(lib_id "antmicroTransistorsFETsMOSFETsSingle:DMG1012T-7")
		(at 87.63 246.38 0)
		(unit 1)
		(exclude_from_sim no)
		(in_bom yes)
		(on_board yes)
		(dnp no)
		(property "Reference" "Q8"
			(at 97.79 242.57 0)
			(effects
				(font
					(size 1.27 1.27)
					(thickness 0.15)
				)
				(justify left)
			)
		)
		(property "Value" "DMG1012T-7"
			(at 97.79 250.19 0)
			(effects
				(font
					(size 1.27 1.27)
					(thickness 0.15)
				)
				(justify left bottom)
				(hide yes)
			)
		)
		(property "Footprint" "antmicro-footprints:SOT-523"
			(at 97.79 252.73 0)
			(effects
				(font
					(size 1.27 1.27)
					(thickness 0.15)
				)
				(justify left bottom)
				(hide yes)
			)
		)
		(property "Datasheet" "https://www.diodes.com/assets/Datasheets/ds31783.pdf"
			(at 97.79 255.27 0)
			(effects
				(font
					(size 1.27 1.27)
					(thickness 0.15)
				)
				(justify left bottom)
				(hide yes)
			)
		)
		(property "Description" "Power MOSFET, N Channel, 20 V, 630 mA, 0.3 ohm, SOT-523, Surface Mount"
			(at 87.63 246.38 0)
			(effects
				(font
					(size 1.27 1.27)
				)
				(hide yes)
			)
		)
		(property "MPN" "DMG1012T-7"
			(at 97.79 257.175 90)
			(effects
				(font
					(size 1.27 1.27)
					(thickness 0.15)
				)
				(justify left)
			)
		)
		(property "Manufacturer" "Diodes Incorporated"
			(at 97.79 247.65 0)
			(effects
				(font
					(size 1.27 1.27)
					(thickness 0.15)
				)
				(justify left bottom)
				(hide yes)
			)
		)
		(property "Author" "Antmicro"
			(at 97.79 257.81 0)
			(effects
				(font
					(size 1.27 1.27)
					(thickness 0.15)
				)
				(justify left bottom)
				(hide yes)
			)
		)
		(property "License" "Apache-2.0"
			(at 97.79 260.35 0)
			(effects
				(font
					(size 1.27 1.27)
					(thickness 0.15)
				)
				(justify left bottom)
				(hide yes)
			)
		)
		(property "Public" ""
			(at 107.95 254 0)
			(effects
				(font
					(size 1.27 1.27)
				)
				(justify left bottom)
				(hide yes)
			)
		)
		(pin "1"
		)
		(pin "2"
		)
		(pin "3"
		)
		(instances
			(project "polarfire-som"
				(path ""
					(reference "Q8")
					(unit 1)
				)
			)
		)
	)
	(symbol
		(lib_id "antmicropower:+3V3")
		(at 334.01 76.2 0)
		(unit 1)
		(exclude_from_sim no)
		(in_bom yes)
		(on_board yes)
		(dnp no)
		(property "Reference" "#PWR0349"
			(at 349.25 78.74 0)
			(effects
				(font
					(size 1.27 1.27)
					(thickness 0.15)
				)
				(justify left bottom)
				(hide yes)
			)
		)
		(property "Value" "+3V3"
			(at 334.01 71.12 0)
			(effects
				(font
					(size 1.27 1.27)
					(thickness 0.15)
				)
			)
		)
		(property "Footprint" ""
			(at 349.25 83.82 0)
			(effects
				(font
					(size 1.27 1.27)
					(thickness 0.15)
				)
				(justify left bottom)
				(hide yes)
			)
		)
		(property "Datasheet" ""
			(at 349.25 86.36 0)
			(effects
				(font
					(size 1.27 1.27)
					(thickness 0.15)
				)
				(justify left bottom)
				(hide yes)
			)
		)
		(property "Description" ""
			(at 334.01 76.2 0)
			(effects
				(font
					(size 1.27 1.27)
				)
				(hide yes)
			)
		)
		(property "Author" "Antmicro"
			(at 349.25 83.82 0)
			(effects
				(font
					(size 1.27 1.27)
					(thickness 0.15)
				)
				(justify left bottom)
				(hide yes)
			)
		)
		(property "License" "Apache-2.0"
			(at 349.25 86.36 0)
			(effects
				(font
					(size 1.27 1.27)
					(thickness 0.15)
				)
				(justify left bottom)
				(hide yes)
			)
		)
		(pin "1"
		)
		(instances
			(project "polarfire-som"
				(path ""
					(reference "#PWR0349")
					(unit 1)
				)
			)
		)
	)
	(symbol
		(lib_id "antmicroResistors0402:R_100k_0402")
		(at 58.42 252.73 270)
		(mirror x)
		(unit 1)
		(exclude_from_sim no)
		(in_bom yes)
		(on_board yes)
		(dnp no)
		(property "Reference" "R81"
			(at 57.15 248.92 90)
			(effects
				(font
					(size 1.27 1.27)
					(thickness 0.15)
				)
				(justify right)
			)
		)
		(property "Value" "R_100k_0402"
			(at 45.72 232.41 0)
			(effects
				(font
					(size 1.27 1.27)
					(thickness 0.15)
				)
				(justify left bottom)
				(hide yes)
			)
		)
		(property "Footprint" "antmicro-footprints:R_0402_1005Metric"
			(at 43.18 232.41 0)
			(effects
				(font
					(size 1.27 1.27)
					(thickness 0.15)
				)
				(justify left bottom)
				(hide yes)
			)
		)
		(property "Datasheet" "https://www.bourns.com/docs/product-datasheets/cr.pdf"
			(at 40.64 232.41 0)
			(effects
				(font
					(size 1.27 1.27)
					(thickness 0.15)
				)
				(justify left bottom)
				(hide yes)
			)
		)
		(property "Description" "SMD Chip Resistor, 100 kohm, ± 1%, 62.5 mW, 0402 [1005 Metric], Thick Film, General Purpose"
			(at 58.42 252.73 0)
			(effects
				(font
					(size 1.27 1.27)
				)
				(hide yes)
			)
		)
		(property "MPN" "CR0402-FX-1003GLF"
			(at 38.1 232.41 0)
			(effects
				(font
					(size 1.27 1.27)
					(thickness 0.15)
				)
				(justify left bottom)
				(hide yes)
			)
		)
		(property "Manufacturer" "Bourns"
			(at 35.56 232.41 0)
			(effects
				(font
					(size 1.27 1.27)
					(thickness 0.15)
				)
				(justify left bottom)
				(hide yes)
			)
		)
		(property "License" "Apache-2.0"
			(at 33.02 232.41 0)
			(effects
				(font
					(size 1.27 1.27)
					(thickness 0.15)
				)
				(justify left bottom)
				(hide yes)
			)
		)
		(property "Author" "Antmicro"
			(at 30.48 232.41 0)
			(effects
				(font
					(size 1.27 1.27)
					(thickness 0.15)
				)
				(justify left bottom)
				(hide yes)
			)
		)
		(property "Val" "100k"
			(at 57.15 251.46 90)
			(effects
				(font
					(size 1.27 1.27)
					(thickness 0.15)
				)
				(justify right)
			)
		)
		(property "Tolerance" "1%"
			(at 48.26 232.41 0)
			(effects
				(font
					(size 1.27 1.27)
				)
				(justify left bottom)
				(hide yes)
			)
		)
		(property "Public" ""
			(at 27.94 232.41 0)
			(effects
				(font
					(size 1.27 1.27)
				)
				(justify left bottom)
				(hide yes)
			)
		)
		(pin "1"
		)
		(pin "2"
		)
		(instances
			(project "polarfire-som"
				(path ""
					(reference "R81")
					(unit 1)
				)
			)
		)
	)
	(symbol
		(lib_id "antmicroLEDIndicationDiscrete:LED_RGB_1204_LTST-S310F2KT_Horizontal")
		(at 69.85 223.52 270)
		(mirror x)
		(unit 1)
		(exclude_from_sim no)
		(in_bom yes)
		(on_board yes)
		(dnp no)
		(property "Reference" "D6"
			(at 77.47 215.265 90)
			(effects
				(font
					(size 1.27 1.27)
					(thickness 0.15)
				)
				(justify left)
			)
		)
		(property "Value" "LED_RGB_1204_LTST-S310F2KT_Horizontal"
			(at 62.23 196.85 0)
			(effects
				(font
					(size 1.27 1.27)
					(thickness 0.15)
				)
				(justify left bottom)
				(hide yes)
			)
		)
		(property "Footprint" "antmicro-footprints:LED_1204_3210Metric_RGB_Horizontal"
			(at 59.69 196.85 0)
			(effects
				(font
					(size 1.27 1.27)
					(thickness 0.15)
				)
				(justify left bottom)
				(hide yes)
			)
		)
		(property "Datasheet" "https://optoelectronics.liteon.com/upload/download/DS22-2003-047/LTST-S310F2KT.PDF"
			(at 57.15 196.85 0)
			(effects
				(font
					(size 1.27 1.27)
					(thickness 0.15)
				)
				(justify left bottom)
				(hide yes)
			)
		)
		(property "Description" "LED, RGB, SMD, 1204, R 30 mA, G 20 mA, B 20 mA, R 2 V, G 3.5 V, B 3.5 V, Common Anode, Side Look"
			(at 69.85 223.52 0)
			(effects
				(font
					(size 1.27 1.27)
				)
				(hide yes)
			)
		)
		(property "MPN" "LTST-S310F2KT"
			(at 77.47 212.725 90)
			(effects
				(font
					(size 1.27 1.27)
					(thickness 0.15)
				)
				(justify left)
			)
		)
		(property "Manufacturer" "Lite-On"
			(at 54.61 196.85 0)
			(effects
				(font
					(size 1.27 1.27)
					(thickness 0.15)
				)
				(justify left bottom)
				(hide yes)
			)
		)
		(property "Author" "Antmicro"
			(at 52.07 196.85 0)
			(effects
				(font
					(size 1.27 1.27)
					(thickness 0.15)
				)
				(justify left bottom)
				(hide yes)
			)
		)
		(property "License" "Apache-2.0"
			(at 49.53 196.85 0)
			(effects
				(font
					(size 1.27 1.27)
					(thickness 0.15)
				)
				(justify left bottom)
				(hide yes)
			)
		)
		(property "Color" "R, G, B"
			(at 71.12 222.25 90)
			(effects
				(font
					(size 1.27 1.27)
				)
				(justify left bottom)
				(hide yes)
			)
		)
		(pin "2"
		)
		(pin "3"
		)
		(pin "4"
		)
		(pin "1"
		)
		(instances
			(project "polarfire-som"
				(path ""
					(reference "D6")
					(unit 1)
				)
			)
		)
	)
	(symbol
		(lib_id "antmicropower:VDDI")
		(at 307.34 101.6 0)
		(mirror y)
		(unit 1)
		(exclude_from_sim no)
		(in_bom yes)
		(on_board yes)
		(dnp no)
		(fields_autoplaced yes)
		(property "Reference" "#PWR0215"
			(at 307.34 105.41 0)
			(effects
				(font
					(size 1.27 1.27)
				)
				(hide yes)
			)
		)
		(property "Value" "VDD"
			(at 307.34 97.155 0)
			(effects
				(font
					(size 1.27 1.27)
				)
			)
		)
		(property "Footprint" ""
			(at 307.34 101.6 0)
			(effects
				(font
					(size 1.27 1.27)
				)
				(hide yes)
			)
		)
		(property "Datasheet" ""
			(at 307.34 101.6 0)
			(effects
				(font
					(size 1.27 1.27)
				)
				(hide yes)
			)
		)
		(property "Description" ""
			(at 307.34 101.6 0)
			(effects
				(font
					(size 1.27 1.27)
				)
				(hide yes)
			)
		)
		(pin "1"
		)
		(instances
			(project "polarfire-som"
				(path ""
					(reference "#PWR0215")
					(unit 1)
				)
			)
		)
	)
	(symbol
		(lib_id "antmicropower:GND")
		(at 332.74 157.48 0)
		(mirror y)
		(unit 1)
		(exclude_from_sim no)
		(in_bom yes)
		(on_board yes)
		(dnp no)
		(property "Reference" "#PWR0333"
			(at 323.85 160.02 0)
			(effects
				(font
					(size 1.27 1.27)
					(thickness 0.15)
				)
				(justify left bottom)
				(hide yes)
			)
		)
		(property "Value" "GND"
			(at 332.74 161.29 0)
			(effects
				(font
					(size 1.27 1.27)
					(thickness 0.15)
				)
			)
		)
		(property "Footprint" ""
			(at 323.85 165.1 0)
			(effects
				(font
					(size 1.27 1.27)
					(thickness 0.15)
				)
				(justify left bottom)
				(hide yes)
			)
		)
		(property "Datasheet" ""
			(at 323.85 170.18 0)
			(effects
				(font
					(size 1.27 1.27)
					(thickness 0.15)
				)
				(justify left bottom)
				(hide yes)
			)
		)
		(property "Description" ""
			(at 332.74 157.48 0)
			(effects
				(font
					(size 1.27 1.27)
				)
				(hide yes)
			)
		)
		(property "Author" "Antmicro"
			(at 323.85 165.1 0)
			(effects
				(font
					(size 1.27 1.27)
					(thickness 0.15)
				)
				(justify left bottom)
				(hide yes)
			)
		)
		(property "License" "Apache-2.0"
			(at 323.85 167.64 0)
			(effects
				(font
					(size 1.27 1.27)
					(thickness 0.15)
				)
				(justify left bottom)
				(hide yes)
			)
		)
		(pin "1"
		)
		(instances
			(project "polarfire-som"
				(path ""
					(reference "#PWR0333")
					(unit 1)
				)
			)
		)
	)
	(symbol
		(lib_id "antmicropower:GND")
		(at 185.42 233.68 0)
		(mirror y)
		(unit 1)
		(exclude_from_sim no)
		(in_bom yes)
		(on_board yes)
		(dnp no)
		(property "Reference" "#PWR0344"
			(at 176.53 236.22 0)
			(effects
				(font
					(size 1.27 1.27)
					(thickness 0.15)
				)
				(justify left bottom)
				(hide yes)
			)
		)
		(property "Value" "GND"
			(at 181.61 234.95 0)
			(effects
				(font
					(size 1.27 1.27)
					(thickness 0.15)
				)
			)
		)
		(property "Footprint" ""
			(at 176.53 241.3 0)
			(effects
				(font
					(size 1.27 1.27)
					(thickness 0.15)
				)
				(justify left bottom)
				(hide yes)
			)
		)
		(property "Datasheet" ""
			(at 176.53 246.38 0)
			(effects
				(font
					(size 1.27 1.27)
					(thickness 0.15)
				)
				(justify left bottom)
				(hide yes)
			)
		)
		(property "Description" ""
			(at 185.42 233.68 0)
			(effects
				(font
					(size 1.27 1.27)
				)
				(hide yes)
			)
		)
		(property "Author" "Antmicro"
			(at 176.53 241.3 0)
			(effects
				(font
					(size 1.27 1.27)
					(thickness 0.15)
				)
				(justify left bottom)
				(hide yes)
			)
		)
		(property "License" "Apache-2.0"
			(at 176.53 243.84 0)
			(effects
				(font
					(size 1.27 1.27)
					(thickness 0.15)
				)
				(justify left bottom)
				(hide yes)
			)
		)
		(pin "1"
		)
		(instances
			(project "polarfire-som"
				(path ""
					(reference "#PWR0344")
					(unit 1)
				)
			)
		)
	)
	(symbol
		(lib_id "antmicroTransistorsFETsMOSFETsSingle:DMG1012T-7")
		(at 59.69 246.38 0)
		(unit 1)
		(exclude_from_sim no)
		(in_bom yes)
		(on_board yes)
		(dnp no)
		(property "Reference" "Q7"
			(at 69.85 242.57 0)
			(effects
				(font
					(size 1.27 1.27)
					(thickness 0.15)
				)
				(justify left)
			)
		)
		(property "Value" "DMG1012T-7"
			(at 69.85 250.19 0)
			(effects
				(font
					(size 1.27 1.27)
					(thickness 0.15)
				)
				(justify left bottom)
				(hide yes)
			)
		)
		(property "Footprint" "antmicro-footprints:SOT-523"
			(at 69.85 252.73 0)
			(effects
				(font
					(size 1.27 1.27)
					(thickness 0.15)
				)
				(justify left bottom)
				(hide yes)
			)
		)
		(property "Datasheet" "https://www.diodes.com/assets/Datasheets/ds31783.pdf"
			(at 69.85 255.27 0)
			(effects
				(font
					(size 1.27 1.27)
					(thickness 0.15)
				)
				(justify left bottom)
				(hide yes)
			)
		)
		(property "Description" "Power MOSFET, N Channel, 20 V, 630 mA, 0.3 ohm, SOT-523, Surface Mount"
			(at 59.69 246.38 0)
			(effects
				(font
					(size 1.27 1.27)
				)
				(hide yes)
			)
		)
		(property "MPN" "DMG1012T-7"
			(at 69.85 257.175 90)
			(effects
				(font
					(size 1.27 1.27)
					(thickness 0.15)
				)
				(justify left)
			)
		)
		(property "Manufacturer" "Diodes Incorporated"
			(at 69.85 247.65 0)
			(effects
				(font
					(size 1.27 1.27)
					(thickness 0.15)
				)
				(justify left bottom)
				(hide yes)
			)
		)
		(property "Author" "Antmicro"
			(at 69.85 257.81 0)
			(effects
				(font
					(size 1.27 1.27)
					(thickness 0.15)
				)
				(justify left bottom)
				(hide yes)
			)
		)
		(property "License" "Apache-2.0"
			(at 69.85 260.35 0)
			(effects
				(font
					(size 1.27 1.27)
					(thickness 0.15)
				)
				(justify left bottom)
				(hide yes)
			)
		)
		(property "Public" ""
			(at 80.01 254 0)
			(effects
				(font
					(size 1.27 1.27)
				)
				(justify left bottom)
				(hide yes)
			)
		)
		(pin "1"
		)
		(pin "2"
		)
		(pin "3"
		)
		(instances
			(project "polarfire-som"
				(path ""
					(reference "Q7")
					(unit 1)
				)
			)
		)
	)
	(symbol
		(lib_id "antmicroLogicTranslatorsLevelShifters:NTS0102_XSON")
		(at 134.62 259.08 0)
		(unit 1)
		(exclude_from_sim no)
		(in_bom yes)
		(on_board yes)
		(dnp no)
		(fields_autoplaced yes)
		(property "Reference" "U29"
			(at 144.78 251.46 0)
			(effects
				(font
					(size 1.27 1.27)
					(thickness 0.15)
				)
			)
		)
		(property "Value" "NTS0102_XSON"
			(at 170.18 266.7 0)
			(effects
				(font
					(size 1.27 1.27)
					(thickness 0.15)
				)
				(justify left bottom)
				(hide yes)
			)
		)
		(property "Footprint" "antmicro-footprints:XSON-8_1x1.95mm_P0.5mm"
			(at 170.18 269.24 0)
			(effects
				(font
					(size 1.27 1.27)
					(thickness 0.15)
				)
				(justify left bottom)
				(hide yes)
			)
		)
		(property "Datasheet" "http://www.farnell.com/datasheets/1760723.pdf"
			(at 170.18 271.78 0)
			(effects
				(font
					(size 1.27 1.27)
					(thickness 0.15)
				)
				(justify left bottom)
				(hide yes)
			)
		)
		(property "Description" "Transceiver, 1.65 V to 3.6 V, XSON-8"
			(at 134.62 259.08 0)
			(effects
				(font
					(size 1.27 1.27)
				)
				(hide yes)
			)
		)
		(property "MPN" "NTS0102GT"
			(at 144.78 254 0)
			(effects
				(font
					(size 1.27 1.27)
					(thickness 0.15)
				)
			)
		)
		(property "Manufacturer" "NXP"
			(at 170.18 274.32 0)
			(effects
				(font
					(size 1.27 1.27)
					(thickness 0.15)
				)
				(justify left bottom)
				(hide yes)
			)
		)
		(property "Author" "Antmicro"
			(at 170.18 276.86 0)
			(effects
				(font
					(size 1.27 1.27)
					(thickness 0.15)
				)
				(justify left bottom)
				(hide yes)
			)
		)
		(property "License" "Apache-2.0"
			(at 170.18 279.4 0)
			(effects
				(font
					(size 1.27 1.27)
					(thickness 0.15)
				)
				(justify left bottom)
				(hide yes)
			)
		)
		(pin "2"
		)
		(pin "6"
		)
		(pin "7"
		)
		(pin "5"
		)
		(pin "4"
		)
		(pin "3"
		)
		(pin "1"
		)
		(pin "8"
		)
		(instances
			(project "polarfire-som"
				(path ""
					(reference "U29")
					(unit 1)
				)
			)
		)
	)
	(symbol
		(lib_id "antmicropower:GND")
		(at 335.28 110.49 0)
		(unit 1)
		(exclude_from_sim no)
		(in_bom yes)
		(on_board yes)
		(dnp no)
		(property "Reference" "#PWR0354"
			(at 344.17 113.03 0)
			(effects
				(font
					(size 1.27 1.27)
					(thickness 0.15)
				)
				(justify left bottom)
				(hide yes)
			)
		)
		(property "Value" "GND"
			(at 339.09 111.76 0)
			(effects
				(font
					(size 1.27 1.27)
					(thickness 0.15)
				)
			)
		)
		(property "Footprint" ""
			(at 344.17 118.11 0)
			(effects
				(font
					(size 1.27 1.27)
					(thickness 0.15)
				)
				(justify left bottom)
				(hide yes)
			)
		)
		(property "Datasheet" ""
			(at 344.17 123.19 0)
			(effects
				(font
					(size 1.27 1.27)
					(thickness 0.15)
				)
				(justify left bottom)
				(hide yes)
			)
		)
		(property "Description" ""
			(at 335.28 110.49 0)
			(effects
				(font
					(size 1.27 1.27)
				)
				(hide yes)
			)
		)
		(property "Author" "Antmicro"
			(at 344.17 118.11 0)
			(effects
				(font
					(size 1.27 1.27)
					(thickness 0.15)
				)
				(justify left bottom)
				(hide yes)
			)
		)
		(property "License" "Apache-2.0"
			(at 344.17 120.65 0)
			(effects
				(font
					(size 1.27 1.27)
					(thickness 0.15)
				)
				(justify left bottom)
				(hide yes)
			)
		)
		(pin "1"
		)
		(instances
			(project "polarfire-som"
				(path ""
					(reference "#PWR0354")
					(unit 1)
				)
			)
		)
	)
	(symbol
		(lib_id "antmicropower:VDDI")
		(at 193.04 223.52 0)
		(unit 1)
		(exclude_from_sim no)
		(in_bom yes)
		(on_board yes)
		(dnp no)
		(property "Reference" "#PWR0345"
			(at 193.04 227.33 0)
			(effects
				(font
					(size 1.27 1.27)
				)
				(hide yes)
			)
		)
		(property "Value" "VDD"
			(at 193.04 218.44 0)
			(effects
				(font
					(size 1.27 1.27)
				)
			)
		)
		(property "Footprint" ""
			(at 193.04 223.52 0)
			(effects
				(font
					(size 1.27 1.27)
				)
				(hide yes)
			)
		)
		(property "Datasheet" ""
			(at 193.04 223.52 0)
			(effects
				(font
					(size 1.27 1.27)
				)
				(hide yes)
			)
		)
		(property "Description" ""
			(at 193.04 223.52 0)
			(effects
				(font
					(size 1.27 1.27)
				)
				(hide yes)
			)
		)
		(pin "1"
		)
		(instances
			(project "polarfire-som"
				(path ""
					(reference "#PWR0345")
					(unit 1)
				)
			)
		)
	)
	(symbol
		(lib_id "antmicropower:+3V3")
		(at 383.54 78.74 0)
		(unit 1)
		(exclude_from_sim no)
		(in_bom yes)
		(on_board yes)
		(dnp no)
		(fields_autoplaced yes)
		(property "Reference" "#PWR0300"
			(at 398.78 81.28 0)
			(effects
				(font
					(size 1.27 1.27)
					(thickness 0.15)
				)
				(justify left bottom)
				(hide yes)
			)
		)
		(property "Value" "+3V3"
			(at 383.54 73.66 0)
			(effects
				(font
					(size 1.27 1.27)
					(thickness 0.15)
				)
			)
		)
		(property "Footprint" ""
			(at 398.78 86.36 0)
			(effects
				(font
					(size 1.27 1.27)
					(thickness 0.15)
				)
				(justify left bottom)
				(hide yes)
			)
		)
		(property "Datasheet" ""
			(at 398.78 88.9 0)
			(effects
				(font
					(size 1.27 1.27)
					(thickness 0.15)
				)
				(justify left bottom)
				(hide yes)
			)
		)
		(property "Description" ""
			(at 383.54 78.74 0)
			(effects
				(font
					(size 1.27 1.27)
				)
				(hide yes)
			)
		)
		(property "Author" "Antmicro"
			(at 398.78 86.36 0)
			(effects
				(font
					(size 1.27 1.27)
					(thickness 0.15)
				)
				(justify left bottom)
				(hide yes)
			)
		)
		(property "License" "Apache-2.0"
			(at 398.78 88.9 0)
			(effects
				(font
					(size 1.27 1.27)
					(thickness 0.15)
				)
				(justify left bottom)
				(hide yes)
			)
		)
		(pin "1"
		)
		(instances
			(project "polarfire-som"
				(path ""
					(reference "#PWR0300")
					(unit 1)
				)
			)
		)
	)
	(symbol
		(lib_id "antmicropower:VDDI")
		(at 308.61 76.2 0)
		(unit 1)
		(exclude_from_sim no)
		(in_bom yes)
		(on_board yes)
		(dnp no)
		(property "Reference" "#PWR0302"
			(at 308.61 80.01 0)
			(effects
				(font
					(size 1.27 1.27)
				)
				(hide yes)
			)
		)
		(property "Value" "VDD"
			(at 308.61 71.755 0)
			(effects
				(font
					(size 1.27 1.27)
				)
			)
		)
		(property "Footprint" ""
			(at 308.61 76.2 0)
			(effects
				(font
					(size 1.27 1.27)
				)
				(hide yes)
			)
		)
		(property "Datasheet" ""
			(at 308.61 76.2 0)
			(effects
				(font
					(size 1.27 1.27)
				)
				(hide yes)
			)
		)
		(property "Description" ""
			(at 308.61 76.2 0)
			(effects
				(font
					(size 1.27 1.27)
				)
				(hide yes)
			)
		)
		(pin "1"
		)
		(instances
			(project "polarfire-som"
				(path ""
					(reference "#PWR0302")
					(unit 1)
				)
			)
		)
	)
	(symbol
		(lib_id "antmicropower:GND")
		(at 332.74 63.5 0)
		(mirror y)
		(unit 1)
		(exclude_from_sim no)
		(in_bom yes)
		(on_board yes)
		(dnp no)
		(fields_autoplaced yes)
		(property "Reference" "#PWR0212"
			(at 323.85 66.04 0)
			(effects
				(font
					(size 1.27 1.27)
					(thickness 0.15)
				)
				(justify left bottom)
				(hide yes)
			)
		)
		(property "Value" "GND"
			(at 332.74 68.58 0)
			(effects
				(font
					(size 1.27 1.27)
					(thickness 0.15)
				)
			)
		)
		(property "Footprint" ""
			(at 323.85 71.12 0)
			(effects
				(font
					(size 1.27 1.27)
					(thickness 0.15)
				)
				(justify left bottom)
				(hide yes)
			)
		)
		(property "Datasheet" ""
			(at 323.85 76.2 0)
			(effects
				(font
					(size 1.27 1.27)
					(thickness 0.15)
				)
				(justify left bottom)
				(hide yes)
			)
		)
		(property "Description" ""
			(at 332.74 63.5 0)
			(effects
				(font
					(size 1.27 1.27)
				)
				(hide yes)
			)
		)
		(property "Author" "Antmicro"
			(at 323.85 71.12 0)
			(effects
				(font
					(size 1.27 1.27)
					(thickness 0.15)
				)
				(justify left bottom)
				(hide yes)
			)
		)
		(property "License" "Apache-2.0"
			(at 323.85 73.66 0)
			(effects
				(font
					(size 1.27 1.27)
					(thickness 0.15)
				)
				(justify left bottom)
				(hide yes)
			)
		)
		(pin "1"
		)
		(instances
			(project "polarfire-som"
				(path ""
					(reference "#PWR0212")
					(unit 1)
				)
			)
		)
	)
	(symbol
		(lib_id "antmicropower:+3V3")
		(at 334.01 219.71 0)
		(unit 1)
		(exclude_from_sim no)
		(in_bom yes)
		(on_board yes)
		(dnp no)
		(fields_autoplaced yes)
		(property "Reference" "#PWR0304"
			(at 349.25 222.25 0)
			(effects
				(font
					(size 1.27 1.27)
					(thickness 0.15)
				)
				(justify left bottom)
				(hide yes)
			)
		)
		(property "Value" "+3V3"
			(at 334.01 214.63 0)
			(effects
				(font
					(size 1.27 1.27)
					(thickness 0.15)
				)
			)
		)
		(property "Footprint" ""
			(at 349.25 227.33 0)
			(effects
				(font
					(size 1.27 1.27)
					(thickness 0.15)
				)
				(justify left bottom)
				(hide yes)
			)
		)
		(property "Datasheet" ""
			(at 349.25 229.87 0)
			(effects
				(font
					(size 1.27 1.27)
					(thickness 0.15)
				)
				(justify left bottom)
				(hide yes)
			)
		)
		(property "Description" ""
			(at 334.01 219.71 0)
			(effects
				(font
					(size 1.27 1.27)
				)
				(hide yes)
			)
		)
		(property "Author" "Antmicro"
			(at 349.25 227.33 0)
			(effects
				(font
					(size 1.27 1.27)
					(thickness 0.15)
				)
				(justify left bottom)
				(hide yes)
			)
		)
		(property "License" "Apache-2.0"
			(at 349.25 229.87 0)
			(effects
				(font
					(size 1.27 1.27)
					(thickness 0.15)
				)
				(justify left bottom)
				(hide yes)
			)
		)
		(pin "1"
		)
		(instances
			(project "polarfire-som"
				(path ""
					(reference "#PWR0304")
					(unit 1)
				)
			)
		)
	)
	(symbol
		(lib_id "antmicropower:+3V3")
		(at 330.2 187.96 0)
		(unit 1)
		(exclude_from_sim no)
		(in_bom yes)
		(on_board yes)
		(dnp no)
		(property "Reference" "#PWR0334"
			(at 345.44 187.96 0)
			(effects
				(font
					(size 1.27 1.27)
					(thickness 0.15)
				)
				(justify left bottom)
				(hide yes)
			)
		)
		(property "Value" "+3V3"
			(at 330.2 184.15 0)
			(effects
				(font
					(size 1.27 1.27)
					(thickness 0.15)
				)
			)
		)
		(property "Footprint" ""
			(at 345.44 195.58 0)
			(effects
				(font
					(size 1.27 1.27)
					(thickness 0.15)
				)
				(justify left bottom)
				(hide yes)
			)
		)
		(property "Datasheet" ""
			(at 345.44 198.12 0)
			(effects
				(font
					(size 1.27 1.27)
					(thickness 0.15)
				)
				(justify left bottom)
				(hide yes)
			)
		)
		(property "Description" ""
			(at 330.2 187.96 0)
			(effects
				(font
					(size 1.27 1.27)
				)
				(hide yes)
			)
		)
		(property "Author" "Antmicro"
			(at 345.44 190.5 0)
			(effects
				(font
					(size 1.27 1.27)
					(thickness 0.15)
				)
				(justify left bottom)
				(hide yes)
			)
		)
		(property "License" "Apache-2.0"
			(at 345.44 193.04 0)
			(effects
				(font
					(size 1.27 1.27)
					(thickness 0.15)
				)
				(justify left bottom)
				(hide yes)
			)
		)
		(pin "1"
		)
		(instances
			(project "polarfire-som"
				(path ""
					(reference "#PWR0334")
					(unit 1)
				)
			)
		)
	)
	(symbol
		(lib_id "antmicropower:VDDI")
		(at 309.88 144.78 0)
		(unit 1)
		(exclude_from_sim no)
		(in_bom yes)
		(on_board yes)
		(dnp no)
		(fields_autoplaced yes)
		(property "Reference" "#PWR0159"
			(at 309.88 148.59 0)
			(effects
				(font
					(size 1.27 1.27)
				)
				(hide yes)
			)
		)
		(property "Value" "VDD"
			(at 309.88 139.7 0)
			(effects
				(font
					(size 1.27 1.27)
				)
			)
		)
		(property "Footprint" ""
			(at 309.88 144.78 0)
			(effects
				(font
					(size 1.27 1.27)
				)
				(hide yes)
			)
		)
		(property "Datasheet" ""
			(at 309.88 144.78 0)
			(effects
				(font
					(size 1.27 1.27)
				)
				(hide yes)
			)
		)
		(property "Description" ""
			(at 309.88 144.78 0)
			(effects
				(font
					(size 1.27 1.27)
				)
				(hide yes)
			)
		)
		(pin "1"
		)
		(instances
			(project "polarfire-som"
				(path ""
					(reference "#PWR0159")
					(unit 1)
				)
			)
		)
	)
	(symbol
		(lib_id "antmicropower:GND")
		(at 373.38 86.36 0)
		(mirror y)
		(unit 1)
		(exclude_from_sim no)
		(in_bom yes)
		(on_board yes)
		(dnp no)
		(property "Reference" "#PWR0252"
			(at 364.49 88.9 0)
			(effects
				(font
					(size 1.27 1.27)
					(thickness 0.15)
				)
				(justify left bottom)
				(hide yes)
			)
		)
		(property "Value" "GND"
			(at 373.38 90.17 0)
			(effects
				(font
					(size 1.27 1.27)
					(thickness 0.15)
				)
			)
		)
		(property "Footprint" ""
			(at 364.49 93.98 0)
			(effects
				(font
					(size 1.27 1.27)
					(thickness 0.15)
				)
				(justify left bottom)
				(hide yes)
			)
		)
		(property "Datasheet" ""
			(at 364.49 99.06 0)
			(effects
				(font
					(size 1.27 1.27)
					(thickness 0.15)
				)
				(justify left bottom)
				(hide yes)
			)
		)
		(property "Description" ""
			(at 373.38 86.36 0)
			(effects
				(font
					(size 1.27 1.27)
				)
				(hide yes)
			)
		)
		(property "Author" "Antmicro"
			(at 364.49 93.98 0)
			(effects
				(font
					(size 1.27 1.27)
					(thickness 0.15)
				)
				(justify left bottom)
				(hide yes)
			)
		)
		(property "License" "Apache-2.0"
			(at 364.49 96.52 0)
			(effects
				(font
					(size 1.27 1.27)
					(thickness 0.15)
				)
				(justify left bottom)
				(hide yes)
			)
		)
		(pin "1"
		)
		(instances
			(project "polarfire-som"
				(path ""
					(reference "#PWR0252")
					(unit 1)
				)
			)
		)
	)
	(symbol
		(lib_id "antmicropower:VDDI")
		(at 133.35 203.2 0)
		(mirror y)
		(unit 1)
		(exclude_from_sim no)
		(in_bom yes)
		(on_board yes)
		(dnp no)
		(fields_autoplaced yes)
		(property "Reference" "#PWR0143"
			(at 133.35 207.01 0)
			(effects
				(font
					(size 1.27 1.27)
				)
				(hide yes)
			)
		)
		(property "Value" "VDD"
			(at 133.35 198.755 0)
			(effects
				(font
					(size 1.27 1.27)
				)
			)
		)
		(property "Footprint" ""
			(at 133.35 203.2 0)
			(effects
				(font
					(size 1.27 1.27)
				)
				(hide yes)
			)
		)
		(property "Datasheet" ""
			(at 133.35 203.2 0)
			(effects
				(font
					(size 1.27 1.27)
				)
				(hide yes)
			)
		)
		(property "Description" ""
			(at 133.35 203.2 0)
			(effects
				(font
					(size 1.27 1.27)
				)
				(hide yes)
			)
		)
		(pin "1"
		)
		(instances
			(project "polarfire-som"
				(path ""
					(reference "#PWR0143")
					(unit 1)
				)
			)
		)
	)
	(symbol
		(lib_id "antmicroCapacitors0402:C_100n_0402")
		(at 359.41 166.37 90)
		(mirror x)
		(unit 1)
		(exclude_from_sim no)
		(in_bom yes)
		(on_board yes)
		(dnp no)
		(property "Reference" "C178"
			(at 355.6 166.37 90)
			(effects
				(font
					(size 1.27 1.27)
					(thickness 0.15)
				)
			)
		)
		(property "Value" "C_100n_0402"
			(at 369.57 186.69 0)
			(effects
				(font
					(size 1.27 1.27)
					(thickness 0.15)
				)
				(justify left bottom)
				(hide yes)
			)
		)
		(property "Footprint" "antmicro-footprints:C_0402_1005Metric"
			(at 372.11 186.69 0)
			(effects
				(font
					(size 1.27 1.27)
					(thickness 0.15)
				)
				(justify left bottom)
				(hide yes)
			)
		)
		(property "Datasheet" "https://www.murata.com/products/productdetail?partno=GRM155R61H104KE14%23"
			(at 374.65 186.69 0)
			(effects
				(font
					(size 1.27 1.27)
					(thickness 0.15)
				)
				(justify left bottom)
				(hide yes)
			)
		)
		(property "Description" "SMD Multilayer Ceramic Capacitor, 0.1 µF, 50 V, 0402 [1005 Metric], ± 10%, X5R, GRM Series"
			(at 359.41 166.37 0)
			(effects
				(font
					(size 1.27 1.27)
				)
				(hide yes)
			)
		)
		(property "MPN" "GRM155R61H104KE14D"
			(at 377.19 186.69 0)
			(effects
				(font
					(size 1.27 1.27)
					(thickness 0.15)
				)
				(justify left bottom)
				(hide yes)
			)
		)
		(property "Manufacturer" "Murata"
			(at 379.73 186.69 0)
			(effects
				(font
					(size 1.27 1.27)
					(thickness 0.15)
				)
				(justify left bottom)
				(hide yes)
			)
		)
		(property "License" "Apache-2.0"
			(at 382.27 186.69 0)
			(effects
				(font
					(size 1.27 1.27)
					(thickness 0.15)
				)
				(justify left bottom)
				(hide yes)
			)
		)
		(property "Author" "Antmicro"
			(at 384.81 186.69 0)
			(effects
				(font
					(size 1.27 1.27)
					(thickness 0.15)
				)
				(justify left bottom)
				(hide yes)
			)
		)
		(property "Val" "100n"
			(at 358.14 171.45 90)
			(effects
				(font
					(size 1.27 1.27)
					(thickness 0.15)
				)
				(justify left bottom)
			)
		)
		(property "Voltage" "50V"
			(at 387.35 186.69 0)
			(effects
				(font
					(size 1.27 1.27)
				)
				(justify left bottom)
				(hide yes)
			)
		)
		(property "Dielectric" "X5R"
			(at 389.89 186.69 0)
			(effects
				(font
					(size 1.27 1.27)
				)
				(justify left bottom)
				(hide yes)
			)
		)
		(property "Public" ""
			(at 392.43 186.69 0)
			(effects
				(font
					(size 1.27 1.27)
				)
				(justify left bottom)
				(hide yes)
			)
		)
		(pin "2"
		)
		(pin "1"
		)
		(instances
			(project "polarfire-som"
				(path ""
					(reference "C178")
					(unit 1)
				)
			)
		)
	)
	(symbol
		(lib_id "antmicropower:VDDI")
		(at 359.41 165.1 0)
		(unit 1)
		(exclude_from_sim no)
		(in_bom yes)
		(on_board yes)
		(dnp no)
		(property "Reference" "#PWR0140"
			(at 359.41 168.91 0)
			(effects
				(font
					(size 1.27 1.27)
				)
				(hide yes)
			)
		)
		(property "Value" "VDD"
			(at 358.775 160.02 0)
			(effects
				(font
					(size 1.27 1.27)
				)
			)
		)
		(property "Footprint" ""
			(at 359.41 165.1 0)
			(effects
				(font
					(size 1.27 1.27)
				)
				(hide yes)
			)
		)
		(property "Datasheet" ""
			(at 359.41 165.1 0)
			(effects
				(font
					(size 1.27 1.27)
				)
				(hide yes)
			)
		)
		(property "Description" ""
			(at 359.41 165.1 0)
			(effects
				(font
					(size 1.27 1.27)
				)
				(hide yes)
			)
		)
		(pin "1"
		)
		(instances
			(project "polarfire-som"
				(path ""
					(reference "#PWR0140")
					(unit 1)
				)
			)
		)
	)
	(symbol
		(lib_id "antmicropower:GND")
		(at 156.21 240.03 0)
		(mirror y)
		(unit 1)
		(exclude_from_sim no)
		(in_bom yes)
		(on_board yes)
		(dnp no)
		(fields_autoplaced yes)
		(property "Reference" "#PWR0312"
			(at 147.32 242.57 0)
			(effects
				(font
					(size 1.27 1.27)
					(thickness 0.15)
				)
				(justify left bottom)
				(hide yes)
			)
		)
		(property "Value" "GND"
			(at 156.21 245.11 0)
			(effects
				(font
					(size 1.27 1.27)
					(thickness 0.15)
				)
			)
		)
		(property "Footprint" ""
			(at 147.32 247.65 0)
			(effects
				(font
					(size 1.27 1.27)
					(thickness 0.15)
				)
				(justify left bottom)
				(hide yes)
			)
		)
		(property "Datasheet" ""
			(at 147.32 252.73 0)
			(effects
				(font
					(size 1.27 1.27)
					(thickness 0.15)
				)
				(justify left bottom)
				(hide yes)
			)
		)
		(property "Description" ""
			(at 156.21 240.03 0)
			(effects
				(font
					(size 1.27 1.27)
				)
				(hide yes)
			)
		)
		(property "Author" "Antmicro"
			(at 147.32 247.65 0)
			(effects
				(font
					(size 1.27 1.27)
					(thickness 0.15)
				)
				(justify left bottom)
				(hide yes)
			)
		)
		(property "License" "Apache-2.0"
			(at 147.32 250.19 0)
			(effects
				(font
					(size 1.27 1.27)
					(thickness 0.15)
				)
				(justify left bottom)
				(hide yes)
			)
		)
		(pin "1"
		)
		(instances
			(project "polarfire-som"
				(path ""
					(reference "#PWR0312")
					(unit 1)
				)
			)
		)
	)
	(symbol
		(lib_id "antmicroLogicTranslatorsLevelShifters:NTS0102_XSON")
		(at 311.15 114.3 0)
		(unit 1)
		(exclude_from_sim no)
		(in_bom yes)
		(on_board yes)
		(dnp no)
		(fields_autoplaced yes)
		(property "Reference" "U21"
			(at 321.31 106.68 0)
			(effects
				(font
					(size 1.27 1.27)
					(thickness 0.15)
				)
			)
		)
		(property "Value" "NTS0102_XSON"
			(at 346.71 121.92 0)
			(effects
				(font
					(size 1.27 1.27)
					(thickness 0.15)
				)
				(justify left bottom)
				(hide yes)
			)
		)
		(property "Footprint" "antmicro-footprints:XSON-8_1x1.95mm_P0.5mm"
			(at 346.71 124.46 0)
			(effects
				(font
					(size 1.27 1.27)
					(thickness 0.15)
				)
				(justify left bottom)
				(hide yes)
			)
		)
		(property "Datasheet" "http://www.farnell.com/datasheets/1760723.pdf"
			(at 346.71 127 0)
			(effects
				(font
					(size 1.27 1.27)
					(thickness 0.15)
				)
				(justify left bottom)
				(hide yes)
			)
		)
		(property "Description" "Transceiver, 1.65 V to 3.6 V, XSON-8"
			(at 311.15 114.3 0)
			(effects
				(font
					(size 1.27 1.27)
				)
				(hide yes)
			)
		)
		(property "MPN" "NTS0102GT"
			(at 321.31 109.22 0)
			(effects
				(font
					(size 1.27 1.27)
					(thickness 0.15)
				)
			)
		)
		(property "Manufacturer" "NXP"
			(at 346.71 129.54 0)
			(effects
				(font
					(size 1.27 1.27)
					(thickness 0.15)
				)
				(justify left bottom)
				(hide yes)
			)
		)
		(property "Author" "Antmicro"
			(at 346.71 132.08 0)
			(effects
				(font
					(size 1.27 1.27)
					(thickness 0.15)
				)
				(justify left bottom)
				(hide yes)
			)
		)
		(property "License" "Apache-2.0"
			(at 346.71 134.62 0)
			(effects
				(font
					(size 1.27 1.27)
					(thickness 0.15)
				)
				(justify left bottom)
				(hide yes)
			)
		)
		(pin "2"
		)
		(pin "6"
		)
		(pin "7"
		)
		(pin "5"
		)
		(pin "4"
		)
		(pin "3"
		)
		(pin "1"
		)
		(pin "8"
		)
		(instances
			(project "polarfire-som"
				(path ""
					(reference "U21")
					(unit 1)
				)
			)
		)
	)
	(symbol
		(lib_id "antmicropower:+3V3")
		(at 156.21 229.87 0)
		(mirror y)
		(unit 1)
		(exclude_from_sim no)
		(in_bom yes)
		(on_board yes)
		(dnp no)
		(fields_autoplaced yes)
		(property "Reference" "#PWR0317"
			(at 140.97 229.87 0)
			(effects
				(font
					(size 1.27 1.27)
					(thickness 0.15)
				)
				(justify left bottom)
				(hide yes)
			)
		)
		(property "Value" "+3V3"
			(at 156.21 224.79 0)
			(effects
				(font
					(size 1.27 1.27)
					(thickness 0.15)
				)
			)
		)
		(property "Footprint" ""
			(at 140.97 237.49 0)
			(effects
				(font
					(size 1.27 1.27)
					(thickness 0.15)
				)
				(justify left bottom)
				(hide yes)
			)
		)
		(property "Datasheet" ""
			(at 140.97 240.03 0)
			(effects
				(font
					(size 1.27 1.27)
					(thickness 0.15)
				)
				(justify left bottom)
				(hide yes)
			)
		)
		(property "Description" ""
			(at 156.21 229.87 0)
			(effects
				(font
					(size 1.27 1.27)
				)
				(hide yes)
			)
		)
		(property "Author" "Antmicro"
			(at 140.97 232.41 0)
			(effects
				(font
					(size 1.27 1.27)
					(thickness 0.15)
				)
				(justify left bottom)
				(hide yes)
			)
		)
		(property "License" "Apache-2.0"
			(at 140.97 234.95 0)
			(effects
				(font
					(size 1.27 1.27)
					(thickness 0.15)
				)
				(justify left bottom)
				(hide yes)
			)
		)
		(pin "1"
		)
		(instances
			(project "polarfire-som"
				(path ""
					(reference "#PWR0317")
					(unit 1)
				)
			)
		)
	)
	(symbol
		(lib_id "antmicroLogicTranslatorsLevelShifters:NTS0102_XSON")
		(at 311.15 222.25 0)
		(unit 1)
		(exclude_from_sim no)
		(in_bom yes)
		(on_board yes)
		(dnp no)
		(fields_autoplaced yes)
		(property "Reference" "U24"
			(at 321.31 214.63 0)
			(effects
				(font
					(size 1.27 1.27)
					(thickness 0.15)
				)
			)
		)
		(property "Value" "NTS0102_XSON"
			(at 346.71 229.87 0)
			(effects
				(font
					(size 1.27 1.27)
					(thickness 0.15)
				)
				(justify left bottom)
				(hide yes)
			)
		)
		(property "Footprint" "antmicro-footprints:XSON-8_1x1.95mm_P0.5mm"
			(at 346.71 232.41 0)
			(effects
				(font
					(size 1.27 1.27)
					(thickness 0.15)
				)
				(justify left bottom)
				(hide yes)
			)
		)
		(property "Datasheet" "http://www.farnell.com/datasheets/1760723.pdf"
			(at 346.71 234.95 0)
			(effects
				(font
					(size 1.27 1.27)
					(thickness 0.15)
				)
				(justify left bottom)
				(hide yes)
			)
		)
		(property "Description" "Transceiver, 1.65 V to 3.6 V, XSON-8"
			(at 311.15 222.25 0)
			(effects
				(font
					(size 1.27 1.27)
				)
				(hide yes)
			)
		)
		(property "MPN" "NTS0102GT"
			(at 321.31 217.17 0)
			(effects
				(font
					(size 1.27 1.27)
					(thickness 0.15)
				)
			)
		)
		(property "Manufacturer" "NXP"
			(at 346.71 237.49 0)
			(effects
				(font
					(size 1.27 1.27)
					(thickness 0.15)
				)
				(justify left bottom)
				(hide yes)
			)
		)
		(property "Author" "Antmicro"
			(at 346.71 240.03 0)
			(effects
				(font
					(size 1.27 1.27)
					(thickness 0.15)
				)
				(justify left bottom)
				(hide yes)
			)
		)
		(property "License" "Apache-2.0"
			(at 346.71 242.57 0)
			(effects
				(font
					(size 1.27 1.27)
					(thickness 0.15)
				)
				(justify left bottom)
				(hide yes)
			)
		)
		(pin "8"
		)
		(pin "7"
		)
		(pin "3"
		)
		(pin "2"
		)
		(pin "1"
		)
		(pin "6"
		)
		(pin "5"
		)
		(pin "4"
		)
		(instances
			(project "polarfire-som"
				(path ""
					(reference "U24")
					(unit 1)
				)
			)
		)
	)
	(symbol
		(lib_id "antmicropower:VDDI")
		(at 133.35 229.87 0)
		(mirror y)
		(unit 1)
		(exclude_from_sim no)
		(in_bom yes)
		(on_board yes)
		(dnp no)
		(fields_autoplaced yes)
		(property "Reference" "#PWR0146"
			(at 133.35 233.68 0)
			(effects
				(font
					(size 1.27 1.27)
				)
				(hide yes)
			)
		)
		(property "Value" "VDD"
			(at 133.35 225.425 0)
			(effects
				(font
					(size 1.27 1.27)
				)
			)
		)
		(property "Footprint" ""
			(at 133.35 229.87 0)
			(effects
				(font
					(size 1.27 1.27)
				)
				(hide yes)
			)
		)
		(property "Datasheet" ""
			(at 133.35 229.87 0)
			(effects
				(font
					(size 1.27 1.27)
				)
				(hide yes)
			)
		)
		(property "Description" ""
			(at 133.35 229.87 0)
			(effects
				(font
					(size 1.27 1.27)
				)
				(hide yes)
			)
		)
		(pin "1"
		)
		(instances
			(project "polarfire-som"
				(path ""
					(reference "#PWR0146")
					(unit 1)
				)
			)
		)
	)
	(symbol
		(lib_id "antmicropower:GND")
		(at 304.8 110.49 0)
		(mirror y)
		(unit 1)
		(exclude_from_sim no)
		(in_bom yes)
		(on_board yes)
		(dnp no)
		(property "Reference" "#PWR0213"
			(at 295.91 113.03 0)
			(effects
				(font
					(size 1.27 1.27)
					(thickness 0.15)
				)
				(justify left bottom)
				(hide yes)
			)
		)
		(property "Value" "GND"
			(at 300.99 111.76 0)
			(effects
				(font
					(size 1.27 1.27)
					(thickness 0.15)
				)
			)
		)
		(property "Footprint" ""
			(at 295.91 118.11 0)
			(effects
				(font
					(size 1.27 1.27)
					(thickness 0.15)
				)
				(justify left bottom)
				(hide yes)
			)
		)
		(property "Datasheet" ""
			(at 295.91 123.19 0)
			(effects
				(font
					(size 1.27 1.27)
					(thickness 0.15)
				)
				(justify left bottom)
				(hide yes)
			)
		)
		(property "Description" ""
			(at 304.8 110.49 0)
			(effects
				(font
					(size 1.27 1.27)
				)
				(hide yes)
			)
		)
		(property "Author" "Antmicro"
			(at 295.91 118.11 0)
			(effects
				(font
					(size 1.27 1.27)
					(thickness 0.15)
				)
				(justify left bottom)
				(hide yes)
			)
		)
		(property "License" "Apache-2.0"
			(at 295.91 120.65 0)
			(effects
				(font
					(size 1.27 1.27)
					(thickness 0.15)
				)
				(justify left bottom)
				(hide yes)
			)
		)
		(pin "1"
		)
		(instances
			(project "polarfire-som"
				(path ""
					(reference "#PWR0213")
					(unit 1)
				)
			)
		)
	)
	(symbol
		(lib_id "antmicroCapacitors0402:C_100n_0402")
		(at 335.28 102.87 270)
		(unit 1)
		(exclude_from_sim no)
		(in_bom yes)
		(on_board yes)
		(dnp no)
		(property "Reference" "C125"
			(at 339.09 102.87 90)
			(effects
				(font
					(size 1.27 1.27)
					(thickness 0.15)
				)
			)
		)
		(property "Value" "C_100n_0402"
			(at 325.12 123.19 0)
			(effects
				(font
					(size 1.27 1.27)
					(thickness 0.15)
				)
				(justify left bottom)
				(hide yes)
			)
		)
		(property "Footprint" "antmicro-footprints:C_0402_1005Metric"
			(at 322.58 123.19 0)
			(effects
				(font
					(size 1.27 1.27)
					(thickness 0.15)
				)
				(justify left bottom)
				(hide yes)
			)
		)
		(property "Datasheet" "https://www.murata.com/products/productdetail?partno=GRM155R61H104KE14%23"
			(at 320.04 123.19 0)
			(effects
				(font
					(size 1.27 1.27)
					(thickness 0.15)
				)
				(justify left bottom)
				(hide yes)
			)
		)
		(property "Description" "SMD Multilayer Ceramic Capacitor, 0.1 µF, 50 V, 0402 [1005 Metric], ± 10%, X5R, GRM Series"
			(at 335.28 102.87 0)
			(effects
				(font
					(size 1.27 1.27)
				)
				(hide yes)
			)
		)
		(property "MPN" "GRM155R61H104KE14D"
			(at 317.5 123.19 0)
			(effects
				(font
					(size 1.27 1.27)
					(thickness 0.15)
				)
				(justify left bottom)
				(hide yes)
			)
		)
		(property "Manufacturer" "Murata"
			(at 314.96 123.19 0)
			(effects
				(font
					(size 1.27 1.27)
					(thickness 0.15)
				)
				(justify left bottom)
				(hide yes)
			)
		)
		(property "License" "Apache-2.0"
			(at 312.42 123.19 0)
			(effects
				(font
					(size 1.27 1.27)
					(thickness 0.15)
				)
				(justify left bottom)
				(hide yes)
			)
		)
		(property "Author" "Antmicro"
			(at 309.88 123.19 0)
			(effects
				(font
					(size 1.27 1.27)
					(thickness 0.15)
				)
				(justify left bottom)
				(hide yes)
			)
		)
		(property "Val" "100n"
			(at 336.55 107.95 90)
			(effects
				(font
					(size 1.27 1.27)
					(thickness 0.15)
				)
				(justify left bottom)
			)
		)
		(property "Voltage" "50V"
			(at 307.34 123.19 0)
			(effects
				(font
					(size 1.27 1.27)
				)
				(justify left bottom)
				(hide yes)
			)
		)
		(property "Dielectric" "X5R"
			(at 304.8 123.19 0)
			(effects
				(font
					(size 1.27 1.27)
				)
				(justify left bottom)
				(hide yes)
			)
		)
		(property "Public" ""
			(at 302.26 123.19 0)
			(effects
				(font
					(size 1.27 1.27)
				)
				(justify left bottom)
				(hide yes)
			)
		)
		(pin "2"
		)
		(pin "1"
		)
		(instances
			(project "polarfire-som"
				(path ""
					(reference "C125")
					(unit 1)
				)
			)
		)
	)
	(symbol
		(lib_id "antmicroTransistorsFETsMOSFETsSingle:DMG1012T-7")
		(at 30.48 246.38 0)
		(unit 1)
		(exclude_from_sim no)
		(in_bom yes)
		(on_board yes)
		(dnp no)
		(property "Reference" "Q5"
			(at 40.64 242.57 0)
			(effects
				(font
					(size 1.27 1.27)
					(thickness 0.15)
				)
				(justify left)
			)
		)
		(property "Value" "DMG1012T-7"
			(at 40.64 250.19 0)
			(effects
				(font
					(size 1.27 1.27)
					(thickness 0.15)
				)
				(justify left bottom)
				(hide yes)
			)
		)
		(property "Footprint" "antmicro-footprints:SOT-523"
			(at 40.64 252.73 0)
			(effects
				(font
					(size 1.27 1.27)
					(thickness 0.15)
				)
				(justify left bottom)
				(hide yes)
			)
		)
		(property "Datasheet" "https://www.diodes.com/assets/Datasheets/ds31783.pdf"
			(at 40.64 255.27 0)
			(effects
				(font
					(size 1.27 1.27)
					(thickness 0.15)
				)
				(justify left bottom)
				(hide yes)
			)
		)
		(property "Description" "Power MOSFET, N Channel, 20 V, 630 mA, 0.3 ohm, SOT-523, Surface Mount"
			(at 30.48 246.38 0)
			(effects
				(font
					(size 1.27 1.27)
				)
				(hide yes)
			)
		)
		(property "MPN" "DMG1012T-7"
			(at 40.64 257.175 90)
			(effects
				(font
					(size 1.27 1.27)
					(thickness 0.15)
				)
				(justify left)
			)
		)
		(property "Manufacturer" "Diodes Incorporated"
			(at 40.64 247.65 0)
			(effects
				(font
					(size 1.27 1.27)
					(thickness 0.15)
				)
				(justify left bottom)
				(hide yes)
			)
		)
		(property "Author" "Antmicro"
			(at 40.64 257.81 0)
			(effects
				(font
					(size 1.27 1.27)
					(thickness 0.15)
				)
				(justify left bottom)
				(hide yes)
			)
		)
		(property "License" "Apache-2.0"
			(at 40.64 260.35 0)
			(effects
				(font
					(size 1.27 1.27)
					(thickness 0.15)
				)
				(justify left bottom)
				(hide yes)
			)
		)
		(property "Public" ""
			(at 50.8 254 0)
			(effects
				(font
					(size 1.27 1.27)
				)
				(justify left bottom)
				(hide yes)
			)
		)
		(pin "1"
		)
		(pin "2"
		)
		(pin "3"
		)
		(instances
			(project "polarfire-som"
				(path ""
					(reference "Q5")
					(unit 1)
				)
			)
		)
	)
	(symbol
		(lib_id "antmicropower:VDDI")
		(at 133.35 257.81 0)
		(mirror y)
		(unit 1)
		(exclude_from_sim no)
		(in_bom yes)
		(on_board yes)
		(dnp no)
		(fields_autoplaced yes)
		(property "Reference" "#PWR0147"
			(at 133.35 261.62 0)
			(effects
				(font
					(size 1.27 1.27)
				)
				(hide yes)
			)
		)
		(property "Value" "VDD"
			(at 133.35 253.365 0)
			(effects
				(font
					(size 1.27 1.27)
				)
			)
		)
		(property "Footprint" ""
			(at 133.35 257.81 0)
			(effects
				(font
					(size 1.27 1.27)
				)
				(hide yes)
			)
		)
		(property "Datasheet" ""
			(at 133.35 257.81 0)
			(effects
				(font
					(size 1.27 1.27)
				)
				(hide yes)
			)
		)
		(property "Description" ""
			(at 133.35 257.81 0)
			(effects
				(font
					(size 1.27 1.27)
				)
				(hide yes)
			)
		)
		(pin "1"
		)
		(instances
			(project "polarfire-som"
				(path ""
					(reference "#PWR0147")
					(unit 1)
				)
			)
		)
	)
	(symbol
		(lib_id "antmicropower:+3V3")
		(at 332.74 147.32 0)
		(mirror y)
		(unit 1)
		(exclude_from_sim no)
		(in_bom yes)
		(on_board yes)
		(dnp no)
		(property "Reference" "#PWR0164"
			(at 317.5 147.32 0)
			(effects
				(font
					(size 1.27 1.27)
					(thickness 0.15)
				)
				(justify left bottom)
				(hide yes)
			)
		)
		(property "Value" "+3V3"
			(at 332.74 143.51 0)
			(effects
				(font
					(size 1.27 1.27)
					(thickness 0.15)
				)
			)
		)
		(property "Footprint" ""
			(at 317.5 154.94 0)
			(effects
				(font
					(size 1.27 1.27)
					(thickness 0.15)
				)
				(justify left bottom)
				(hide yes)
			)
		)
		(property "Datasheet" ""
			(at 317.5 157.48 0)
			(effects
				(font
					(size 1.27 1.27)
					(thickness 0.15)
				)
				(justify left bottom)
				(hide yes)
			)
		)
		(property "Description" ""
			(at 332.74 147.32 0)
			(effects
				(font
					(size 1.27 1.27)
				)
				(hide yes)
			)
		)
		(property "Author" "Antmicro"
			(at 317.5 149.86 0)
			(effects
				(font
					(size 1.27 1.27)
					(thickness 0.15)
				)
				(justify left bottom)
				(hide yes)
			)
		)
		(property "License" "Apache-2.0"
			(at 317.5 152.4 0)
			(effects
				(font
					(size 1.27 1.27)
					(thickness 0.15)
				)
				(justify left bottom)
				(hide yes)
			)
		)
		(pin "1"
		)
		(instances
			(project "polarfire-som"
				(path ""
					(reference "#PWR0164")
					(unit 1)
				)
			)
		)
	)
	(symbol
		(lib_id "antmicroResistors0402:R_100k_0402")
		(at 86.36 254 270)
		(mirror x)
		(unit 1)
		(exclude_from_sim no)
		(in_bom yes)
		(on_board yes)
		(dnp no)
		(property "Reference" "R82"
			(at 85.09 250.19 90)
			(effects
				(font
					(size 1.27 1.27)
					(thickness 0.15)
				)
				(justify right)
			)
		)
		(property "Value" "R_100k_0402"
			(at 73.66 233.68 0)
			(effects
				(font
					(size 1.27 1.27)
					(thickness 0.15)
				)
				(justify left bottom)
				(hide yes)
			)
		)
		(property "Footprint" "antmicro-footprints:R_0402_1005Metric"
			(at 71.12 233.68 0)
			(effects
				(font
					(size 1.27 1.27)
					(thickness 0.15)
				)
				(justify left bottom)
				(hide yes)
			)
		)
		(property "Datasheet" "https://www.bourns.com/docs/product-datasheets/cr.pdf"
			(at 68.58 233.68 0)
			(effects
				(font
					(size 1.27 1.27)
					(thickness 0.15)
				)
				(justify left bottom)
				(hide yes)
			)
		)
		(property "Description" "SMD Chip Resistor, 100 kohm, ± 1%, 62.5 mW, 0402 [1005 Metric], Thick Film, General Purpose"
			(at 86.36 254 0)
			(effects
				(font
					(size 1.27 1.27)
				)
				(hide yes)
			)
		)
		(property "MPN" "CR0402-FX-1003GLF"
			(at 66.04 233.68 0)
			(effects
				(font
					(size 1.27 1.27)
					(thickness 0.15)
				)
				(justify left bottom)
				(hide yes)
			)
		)
		(property "Manufacturer" "Bourns"
			(at 63.5 233.68 0)
			(effects
				(font
					(size 1.27 1.27)
					(thickness 0.15)
				)
				(justify left bottom)
				(hide yes)
			)
		)
		(property "License" "Apache-2.0"
			(at 60.96 233.68 0)
			(effects
				(font
					(size 1.27 1.27)
					(thickness 0.15)
				)
				(justify left bottom)
				(hide yes)
			)
		)
		(property "Author" "Antmicro"
			(at 58.42 233.68 0)
			(effects
				(font
					(size 1.27 1.27)
					(thickness 0.15)
				)
				(justify left bottom)
				(hide yes)
			)
		)
		(property "Val" "100k"
			(at 85.09 252.73 90)
			(effects
				(font
					(size 1.27 1.27)
					(thickness 0.15)
				)
				(justify right)
			)
		)
		(property "Tolerance" "1%"
			(at 76.2 233.68 0)
			(effects
				(font
					(size 1.27 1.27)
				)
				(justify left bottom)
				(hide yes)
			)
		)
		(property "Public" ""
			(at 55.88 233.68 0)
			(effects
				(font
					(size 1.27 1.27)
				)
				(justify left bottom)
				(hide yes)
			)
		)
		(pin "1"
		)
		(pin "2"
		)
		(instances
			(project "polarfire-som"
				(path ""
					(reference "R82")
					(unit 1)
				)
			)
		)
	)
	(symbol
		(lib_id "antmicropower:+3V3")
		(at 185.42 223.52 0)
		(unit 1)
		(exclude_from_sim no)
		(in_bom yes)
		(on_board yes)
		(dnp no)
		(property "Reference" "#PWR0343"
			(at 200.66 223.52 0)
			(effects
				(font
					(size 1.27 1.27)
					(thickness 0.15)
				)
				(justify left bottom)
				(hide yes)
			)
		)
		(property "Value" "+3V3"
			(at 185.42 218.44 0)
			(effects
				(font
					(size 1.27 1.27)
					(thickness 0.15)
				)
			)
		)
		(property "Footprint" ""
			(at 200.66 231.14 0)
			(effects
				(font
					(size 1.27 1.27)
					(thickness 0.15)
				)
				(justify left bottom)
				(hide yes)
			)
		)
		(property "Datasheet" ""
			(at 200.66 233.68 0)
			(effects
				(font
					(size 1.27 1.27)
					(thickness 0.15)
				)
				(justify left bottom)
				(hide yes)
			)
		)
		(property "Description" ""
			(at 185.42 223.52 0)
			(effects
				(font
					(size 1.27 1.27)
				)
				(hide yes)
			)
		)
		(property "Author" "Antmicro"
			(at 200.66 226.06 0)
			(effects
				(font
					(size 1.27 1.27)
					(thickness 0.15)
				)
				(justify left bottom)
				(hide yes)
			)
		)
		(property "License" "Apache-2.0"
			(at 200.66 228.6 0)
			(effects
				(font
					(size 1.27 1.27)
					(thickness 0.15)
				)
				(justify left bottom)
				(hide yes)
			)
		)
		(pin "1"
		)
		(instances
			(project "polarfire-som"
				(path ""
					(reference "#PWR0343")
					(unit 1)
				)
			)
		)
	)
	(symbol
		(lib_id "antmicropower:GND")
		(at 311.15 195.58 0)
		(unit 1)
		(exclude_from_sim no)
		(in_bom yes)
		(on_board yes)
		(dnp no)
		(property "Reference" "#PWR0163"
			(at 320.04 198.12 0)
			(effects
				(font
					(size 1.27 1.27)
					(thickness 0.15)
				)
				(justify left bottom)
				(hide yes)
			)
		)
		(property "Value" "GND"
			(at 311.15 199.39 0)
			(effects
				(font
					(size 1.27 1.27)
					(thickness 0.15)
				)
			)
		)
		(property "Footprint" ""
			(at 320.04 203.2 0)
			(effects
				(font
					(size 1.27 1.27)
					(thickness 0.15)
				)
				(justify left bottom)
				(hide yes)
			)
		)
		(property "Datasheet" ""
			(at 320.04 208.28 0)
			(effects
				(font
					(size 1.27 1.27)
					(thickness 0.15)
				)
				(justify left bottom)
				(hide yes)
			)
		)
		(property "Description" ""
			(at 311.15 195.58 0)
			(effects
				(font
					(size 1.27 1.27)
				)
				(hide yes)
			)
		)
		(property "Author" "Antmicro"
			(at 320.04 203.2 0)
			(effects
				(font
					(size 1.27 1.27)
					(thickness 0.15)
				)
				(justify left bottom)
				(hide yes)
			)
		)
		(property "License" "Apache-2.0"
			(at 320.04 205.74 0)
			(effects
				(font
					(size 1.27 1.27)
					(thickness 0.15)
				)
				(justify left bottom)
				(hide yes)
			)
		)
		(pin "1"
		)
		(instances
			(project "polarfire-som"
				(path ""
					(reference "#PWR0163")
					(unit 1)
				)
			)
		)
	)
	(symbol
		(lib_id "antmicropower:+3V3")
		(at 378.46 222.25 0)
		(unit 1)
		(exclude_from_sim no)
		(in_bom yes)
		(on_board yes)
		(dnp no)
		(fields_autoplaced yes)
		(property "Reference" "#PWR0350"
			(at 393.7 224.79 0)
			(effects
				(font
					(size 1.27 1.27)
					(thickness 0.15)
				)
				(justify left bottom)
				(hide yes)
			)
		)
		(property "Value" "+3V3"
			(at 378.46 217.17 0)
			(effects
				(font
					(size 1.27 1.27)
					(thickness 0.15)
				)
			)
		)
		(property "Footprint" ""
			(at 393.7 229.87 0)
			(effects
				(font
					(size 1.27 1.27)
					(thickness 0.15)
				)
				(justify left bottom)
				(hide yes)
			)
		)
		(property "Datasheet" ""
			(at 393.7 232.41 0)
			(effects
				(font
					(size 1.27 1.27)
					(thickness 0.15)
				)
				(justify left bottom)
				(hide yes)
			)
		)
		(property "Description" ""
			(at 378.46 222.25 0)
			(effects
				(font
					(size 1.27 1.27)
				)
				(hide yes)
			)
		)
		(property "Author" "Antmicro"
			(at 393.7 229.87 0)
			(effects
				(font
					(size 1.27 1.27)
					(thickness 0.15)
				)
				(justify left bottom)
				(hide yes)
			)
		)
		(property "License" "Apache-2.0"
			(at 393.7 232.41 0)
			(effects
				(font
					(size 1.27 1.27)
					(thickness 0.15)
				)
				(justify left bottom)
				(hide yes)
			)
		)
		(pin "1"
		)
		(instances
			(project "polarfire-som"
				(path ""
					(reference "#PWR0350")
					(unit 1)
				)
			)
		)
	)
	(symbol
		(lib_id "antmicropower:VDDI")
		(at 308.61 219.71 0)
		(unit 1)
		(exclude_from_sim no)
		(in_bom yes)
		(on_board yes)
		(dnp no)
		(fields_autoplaced yes)
		(property "Reference" "#PWR0251"
			(at 308.61 223.52 0)
			(effects
				(font
					(size 1.27 1.27)
				)
				(hide yes)
			)
		)
		(property "Value" "VDD"
			(at 308.61 215.265 0)
			(effects
				(font
					(size 1.27 1.27)
				)
			)
		)
		(property "Footprint" ""
			(at 308.61 219.71 0)
			(effects
				(font
					(size 1.27 1.27)
				)
				(hide yes)
			)
		)
		(property "Datasheet" ""
			(at 308.61 219.71 0)
			(effects
				(font
					(size 1.27 1.27)
				)
				(hide yes)
			)
		)
		(property "Description" ""
			(at 308.61 219.71 0)
			(effects
				(font
					(size 1.27 1.27)
				)
				(hide yes)
			)
		)
		(pin "1"
		)
		(instances
			(project "polarfire-som"
				(path ""
					(reference "#PWR0251")
					(unit 1)
				)
			)
		)
	)
	(symbol
		(lib_id "antmicropower:+3V3")
		(at 332.74 39.37 0)
		(mirror y)
		(unit 1)
		(exclude_from_sim no)
		(in_bom yes)
		(on_board yes)
		(dnp no)
		(fields_autoplaced yes)
		(property "Reference" "#PWR0211"
			(at 317.5 39.37 0)
			(effects
				(font
					(size 1.27 1.27)
					(thickness 0.15)
				)
				(justify left bottom)
				(hide yes)
			)
		)
		(property "Value" "+3V3"
			(at 332.74 34.29 0)
			(effects
				(font
					(size 1.27 1.27)
					(thickness 0.15)
				)
			)
		)
		(property "Footprint" ""
			(at 317.5 46.99 0)
			(effects
				(font
					(size 1.27 1.27)
					(thickness 0.15)
				)
				(justify left bottom)
				(hide yes)
			)
		)
		(property "Datasheet" ""
			(at 317.5 49.53 0)
			(effects
				(font
					(size 1.27 1.27)
					(thickness 0.15)
				)
				(justify left bottom)
				(hide yes)
			)
		)
		(property "Description" ""
			(at 332.74 39.37 0)
			(effects
				(font
					(size 1.27 1.27)
				)
				(hide yes)
			)
		)
		(property "Author" "Antmicro"
			(at 317.5 41.91 0)
			(effects
				(font
					(size 1.27 1.27)
					(thickness 0.15)
				)
				(justify left bottom)
				(hide yes)
			)
		)
		(property "License" "Apache-2.0"
			(at 317.5 44.45 0)
			(effects
				(font
					(size 1.27 1.27)
					(thickness 0.15)
				)
				(justify left bottom)
				(hide yes)
			)
		)
		(pin "1"
		)
		(instances
			(project "polarfire-som"
				(path ""
					(reference "#PWR0211")
					(unit 1)
				)
			)
		)
	)
	(symbol
		(lib_id "antmicroLogicTranslatorsLevelShifters:NTS0102_XSON")
		(at 134.62 231.14 0)
		(unit 1)
		(exclude_from_sim no)
		(in_bom yes)
		(on_board yes)
		(dnp no)
		(fields_autoplaced yes)
		(property "Reference" "U27"
			(at 144.78 223.52 0)
			(effects
				(font
					(size 1.27 1.27)
					(thickness 0.15)
				)
			)
		)
		(property "Value" "NTS0102_XSON"
			(at 170.18 238.76 0)
			(effects
				(font
					(size 1.27 1.27)
					(thickness 0.15)
				)
				(justify left bottom)
				(hide yes)
			)
		)
		(property "Footprint" "antmicro-footprints:XSON-8_1x1.95mm_P0.5mm"
			(at 170.18 241.3 0)
			(effects
				(font
					(size 1.27 1.27)
					(thickness 0.15)
				)
				(justify left bottom)
				(hide yes)
			)
		)
		(property "Datasheet" "http://www.farnell.com/datasheets/1760723.pdf"
			(at 170.18 243.84 0)
			(effects
				(font
					(size 1.27 1.27)
					(thickness 0.15)
				)
				(justify left bottom)
				(hide yes)
			)
		)
		(property "Description" "Transceiver, 1.65 V to 3.6 V, XSON-8"
			(at 134.62 231.14 0)
			(effects
				(font
					(size 1.27 1.27)
				)
				(hide yes)
			)
		)
		(property "MPN" "NTS0102GT"
			(at 144.78 226.06 0)
			(effects
				(font
					(size 1.27 1.27)
					(thickness 0.15)
				)
			)
		)
		(property "Manufacturer" "NXP"
			(at 170.18 246.38 0)
			(effects
				(font
					(size 1.27 1.27)
					(thickness 0.15)
				)
				(justify left bottom)
				(hide yes)
			)
		)
		(property "Author" "Antmicro"
			(at 170.18 248.92 0)
			(effects
				(font
					(size 1.27 1.27)
					(thickness 0.15)
				)
				(justify left bottom)
				(hide yes)
			)
		)
		(property "License" "Apache-2.0"
			(at 170.18 251.46 0)
			(effects
				(font
					(size 1.27 1.27)
					(thickness 0.15)
				)
				(justify left bottom)
				(hide yes)
			)
		)
		(pin "2"
		)
		(pin "6"
		)
		(pin "7"
		)
		(pin "5"
		)
		(pin "4"
		)
		(pin "3"
		)
		(pin "1"
		)
		(pin "8"
		)
		(instances
			(project "polarfire-som"
				(path ""
					(reference "U27")
					(unit 1)
				)
			)
		)
	)
)
